G04 ================== begin FILE IDENTIFICATION RECORD ==================*
G04 Layout Name:  9324_DA0F0TMBIJ0_F0T_Motherboard_J_v01_20230324_0910.brd*
G04 Film Name:    panel*
G04 File Format:  Gerber RS274X*
G04 File Origin:  Cadence Allegro 17.2-S081*
G04 Origin Date:  Sat Mar 25 08:45:05 2023*
G04 *
G04 Layer:  DRAWING FORMAT/TITLE_BLOCK_A*
G04 Layer:  MANUFACTURING/PHOTOPLOT_OUTLINE*
G04 Layer:  DRAWING FORMAT/TITLE_BLOCK*
G04 Layer:  DRAWING FORMAT/TITLE_DATA_PANEL*
G04 Layer:  BOARD GEOMETRY/ASSEMBLY_NOTES*
G04 *
G04 Offset:    (0.00 0.00)*
G04 Mirror:    No*
G04 Mode:      Positive*
G04 Rotation:  0*
G04 FullContactRelief:  No*
G04 UndefLineWidth:     6.00*
G04 ================== end FILE IDENTIFICATION RECORD ====================*
%FSLAX25Y25*MOIN*%
%IR0*IPPOS*OFA0.00000B0.00000*MIA0B0*SFA1.00000B1.00000*%
%ADD10C,.006*%
G75*
%LPD*%
G75*
G36*
G01X49212Y-29134D02*
G02I-1968J0D01*
G37*
G36*
G01X1792520Y1803261D02*
G02I-1969J0D01*
G37*
G36*
G01X2036614D02*
G02I-1969J0D01*
G37*
G36*
G01X2478562Y83440D02*
G02I-1969J0D01*
G37*
G54D10*
G01X-9843Y1822946D02*
X-80079D01*
G01X-2990Y1783576D02*
X-39390D01*
G01X-6350Y-464479D02*
Y-539479D01*
X493650D01*
Y-464479D01*
X-6350D01*
G01X-12281Y-144553D02*
X-19777Y-144312D01*
X-19702Y-141980D01*
X-19303Y-141246D01*
X-18789Y-140795D01*
X-17783Y-140641D01*
X-16790Y-140860D01*
X-16183Y-141440D01*
X-15829Y-142105D01*
X-15904Y-144437D01*
G01X-15829Y-142105D02*
X-12161Y-140822D01*
G01X-18284Y-136763D02*
X-19015Y-136179D01*
X-19369Y-135514D01*
X-19470Y-134764D01*
X-19190Y-133839D01*
X-18545Y-133206D01*
X-17789Y-133044D01*
X-17042Y-133161D01*
X-16430Y-133554D01*
X-15240Y-135460D01*
X-14393Y-136328D01*
X-13161Y-136928D01*
X-12043Y-137150D01*
X-11917Y-133232D01*
G01X-11829Y-130494D02*
X-16826Y-130333D01*
G01X-15452Y-130378D02*
X-16068Y-130078D01*
X-16552Y-129595D01*
X-16781Y-128934D01*
X-16510Y-128289D01*
X-15996Y-127839D01*
X-15362Y-127579D01*
X-11739Y-127696D01*
G01X-15362Y-127579D02*
X-15978Y-127279D01*
X-16463Y-126797D01*
X-16691Y-126136D01*
X-16421Y-125491D01*
X-15906Y-125040D01*
X-15147Y-124784D01*
X-11649Y-124897D01*
G01X-11588Y-122998D02*
X-16585Y-122837D01*
G01X-15211Y-122882D02*
X-15827Y-122582D01*
X-16311Y-122099D01*
X-16540Y-121438D01*
X-16269Y-120793D01*
X-15755Y-120343D01*
X-15121Y-120083D01*
X-11498Y-120200D01*
G01X-15121Y-120083D02*
X-15737Y-119783D01*
X-16222Y-119301D01*
X-16450Y-118640D01*
X-16180Y-117995D01*
X-15665Y-117544D01*
X-14906Y-117288D01*
X-11408Y-117401D01*
G01X5650Y-529479D02*
Y-534479D01*
G01X4193Y-529479D02*
X7107D01*
G01X12017Y-534479D02*
X9483D01*
Y-529479D01*
X12017D01*
G01X11003Y-531896D02*
X9483D01*
G01X14583Y-529479D02*
Y-534479D01*
X17117D01*
G01X20950Y-534646D02*
X20823Y-534562D01*
Y-534396D01*
X20950Y-534312D01*
X21077Y-534396D01*
Y-534562D01*
X20950Y-534646D01*
G01Y-532396D02*
X20823Y-532312D01*
Y-532146D01*
X20950Y-532062D01*
X21077Y-532146D01*
Y-532312D01*
X20950Y-532396D01*
G01X25733Y-536146D02*
X25100Y-535312D01*
X24783Y-534479D01*
Y-531146D01*
X25100Y-530312D01*
X25733Y-529479D01*
G01X31150D02*
X30643Y-529646D01*
X30263Y-530062D01*
X30010Y-530562D01*
X29820Y-531229D01*
X29757Y-531979D01*
X29820Y-532729D01*
X30010Y-533396D01*
X30263Y-533896D01*
X30643Y-534312D01*
X31150Y-534479D01*
X31657Y-534312D01*
X32037Y-533896D01*
X32290Y-533396D01*
X32480Y-532729D01*
X32543Y-531979D01*
X32480Y-531229D01*
X32290Y-530562D01*
X32037Y-530062D01*
X31657Y-529646D01*
X31150Y-529479D01*
G01X34857Y-533479D02*
X35237Y-534062D01*
X35743Y-534396D01*
X36313Y-534479D01*
X36820Y-534396D01*
X37327Y-533979D01*
X37643Y-533479D01*
X37707Y-532979D01*
X37580Y-532396D01*
X37137Y-531979D01*
X36693Y-531812D01*
X36123D01*
G01X36693D02*
X37073Y-531562D01*
X37390Y-531146D01*
X37517Y-530646D01*
X37390Y-530146D01*
X37073Y-529729D01*
X36503Y-529479D01*
X35933Y-529562D01*
X35363Y-529896D01*
G01X41667Y-536146D02*
X42300Y-535312D01*
X42617Y-534479D01*
Y-531146D01*
X42300Y-530312D01*
X41667Y-529479D01*
G01X45057Y-533479D02*
X45437Y-534062D01*
X45943Y-534396D01*
X46513Y-534479D01*
X47020Y-534396D01*
X47527Y-533979D01*
X47843Y-533479D01*
X47907Y-532979D01*
X47780Y-532396D01*
X47337Y-531979D01*
X46893Y-531812D01*
X46323D01*
G01X46893D02*
X47273Y-531562D01*
X47590Y-531146D01*
X47717Y-530646D01*
X47590Y-530146D01*
X47273Y-529729D01*
X46703Y-529479D01*
X46133Y-529562D01*
X45563Y-529896D01*
G01X50347Y-530312D02*
X50727Y-529812D01*
X51170Y-529562D01*
X51677Y-529479D01*
X52310Y-529646D01*
X52753Y-530062D01*
X52880Y-530562D01*
X52817Y-531062D01*
X52563Y-531479D01*
X51297Y-532312D01*
X50727Y-532896D01*
X50347Y-533729D01*
X50220Y-534479D01*
X52880D01*
G01X56523D02*
X56650Y-533396D01*
X56840Y-532479D01*
X57093Y-531646D01*
X57410Y-530729D01*
X57917Y-529479D01*
X55383D01*
G01X60927Y-532812D02*
X62573D01*
G01X65647Y-530312D02*
X66027Y-529812D01*
X66470Y-529562D01*
X66977Y-529479D01*
X67610Y-529646D01*
X68053Y-530062D01*
X68180Y-530562D01*
X68117Y-531062D01*
X67863Y-531479D01*
X66597Y-532312D01*
X66027Y-532896D01*
X65647Y-533729D01*
X65520Y-534479D01*
X68180D01*
G01X70557Y-533479D02*
X70937Y-534062D01*
X71443Y-534396D01*
X72013Y-534479D01*
X72520Y-534396D01*
X73027Y-533979D01*
X73343Y-533479D01*
X73407Y-532979D01*
X73280Y-532396D01*
X72837Y-531979D01*
X72393Y-531812D01*
X71823D01*
G01X72393D02*
X72773Y-531562D01*
X73090Y-531146D01*
X73217Y-530646D01*
X73090Y-530146D01*
X72773Y-529729D01*
X72203Y-529479D01*
X71633Y-529562D01*
X71063Y-529896D01*
G01X77810Y-534479D02*
Y-529479D01*
X75467Y-533062D01*
X78633D01*
G01X80757Y-533729D02*
X81137Y-534146D01*
X81580Y-534396D01*
X82150Y-534479D01*
X82720Y-534312D01*
X83163Y-533979D01*
X83480Y-533396D01*
X83543Y-532729D01*
X83417Y-532062D01*
X83100Y-531646D01*
X82657Y-531312D01*
X82213Y-531229D01*
X81770Y-531312D01*
X81200Y-531646D01*
X81390Y-529479D01*
X83100D01*
G01X91147Y-534479D02*
Y-529479D01*
X93553D01*
G01X92667Y-531896D02*
X91147D01*
G01X95867Y-534479D02*
X97450Y-529479D01*
X99033Y-534479D01*
G01X98463Y-532729D02*
X96437D01*
G01X101220Y-534479D02*
X103880Y-529479D01*
G01X101220D02*
X103880Y-534479D01*
G01X107650Y-534646D02*
X107523Y-534562D01*
Y-534396D01*
X107650Y-534312D01*
X107777Y-534396D01*
Y-534562D01*
X107650Y-534646D01*
G01Y-532396D02*
X107523Y-532312D01*
Y-532146D01*
X107650Y-532062D01*
X107777Y-532146D01*
Y-532312D01*
X107650Y-532396D01*
G01X112433Y-536146D02*
X111800Y-535312D01*
X111483Y-534479D01*
Y-531146D01*
X111800Y-530312D01*
X112433Y-529479D01*
G01X117850D02*
X117343Y-529646D01*
X116963Y-530062D01*
X116710Y-530562D01*
X116520Y-531229D01*
X116457Y-531979D01*
X116520Y-532729D01*
X116710Y-533396D01*
X116963Y-533896D01*
X117343Y-534312D01*
X117850Y-534479D01*
X118357Y-534312D01*
X118737Y-533896D01*
X118990Y-533396D01*
X119180Y-532729D01*
X119243Y-531979D01*
X119180Y-531229D01*
X118990Y-530562D01*
X118737Y-530062D01*
X118357Y-529646D01*
X117850Y-529479D01*
G01X121557Y-533479D02*
X121937Y-534062D01*
X122443Y-534396D01*
X123013Y-534479D01*
X123520Y-534396D01*
X124027Y-533979D01*
X124343Y-533479D01*
X124407Y-532979D01*
X124280Y-532396D01*
X123837Y-531979D01*
X123393Y-531812D01*
X122823D01*
G01X123393D02*
X123773Y-531562D01*
X124090Y-531146D01*
X124217Y-530646D01*
X124090Y-530146D01*
X123773Y-529729D01*
X123203Y-529479D01*
X122633Y-529562D01*
X122063Y-529896D01*
G01X128367Y-536146D02*
X129000Y-535312D01*
X129317Y-534479D01*
Y-531146D01*
X129000Y-530312D01*
X128367Y-529479D01*
G01X131757Y-533479D02*
X132137Y-534062D01*
X132643Y-534396D01*
X133213Y-534479D01*
X133720Y-534396D01*
X134227Y-533979D01*
X134543Y-533479D01*
X134607Y-532979D01*
X134480Y-532396D01*
X134037Y-531979D01*
X133593Y-531812D01*
X133023D01*
G01X133593D02*
X133973Y-531562D01*
X134290Y-531146D01*
X134417Y-530646D01*
X134290Y-530146D01*
X133973Y-529729D01*
X133403Y-529479D01*
X132833Y-529562D01*
X132263Y-529896D01*
G01X137173Y-533896D02*
X137617Y-534312D01*
X138123Y-534479D01*
X138630Y-534312D01*
X139073Y-533812D01*
X139390Y-533062D01*
X139517Y-532312D01*
Y-531396D01*
X139390Y-530646D01*
X139073Y-529979D01*
X138693Y-529646D01*
X138250Y-529479D01*
X137743Y-529646D01*
X137363Y-529979D01*
X137110Y-530479D01*
X136983Y-531146D01*
X137110Y-531729D01*
X137427Y-532312D01*
X137807Y-532646D01*
X138250Y-532729D01*
X138757Y-532562D01*
X139137Y-532146D01*
X139517Y-531396D01*
G01X143223Y-534479D02*
X143350Y-533396D01*
X143540Y-532479D01*
X143793Y-531646D01*
X144110Y-530729D01*
X144617Y-529479D01*
X142083D01*
G01X147627Y-532812D02*
X149273D01*
G01X152157Y-533479D02*
X152537Y-534062D01*
X153043Y-534396D01*
X153613Y-534479D01*
X154120Y-534396D01*
X154627Y-533979D01*
X154943Y-533479D01*
X155007Y-532979D01*
X154880Y-532396D01*
X154437Y-531979D01*
X153993Y-531812D01*
X153423D01*
G01X153993D02*
X154373Y-531562D01*
X154690Y-531146D01*
X154817Y-530646D01*
X154690Y-530146D01*
X154373Y-529729D01*
X153803Y-529479D01*
X153233Y-529562D01*
X152663Y-529896D01*
G01X157447Y-532396D02*
X157890Y-531812D01*
X158270Y-531479D01*
X158777Y-531312D01*
X159220Y-531479D01*
X159537Y-531812D01*
X159790Y-532312D01*
X159853Y-532896D01*
X159790Y-533396D01*
X159537Y-533896D01*
X159157Y-534312D01*
X158713Y-534479D01*
X158207Y-534312D01*
X157763Y-533812D01*
X157510Y-533062D01*
X157447Y-532229D01*
X157573Y-531146D01*
X157763Y-530562D01*
X158080Y-529979D01*
X158523Y-529562D01*
X158967Y-529479D01*
X159410Y-529646D01*
X159727Y-530062D01*
G01X163750Y-534479D02*
Y-529479D01*
X162990Y-530479D01*
G01Y-534479D02*
X164510D01*
G01X169610D02*
Y-529479D01*
X167267Y-533062D01*
X170433D01*
G01X3643Y-47586D02*
X163Y-155842D01*
G01X5596Y-63405D02*
X3643Y-47586D01*
X677Y-63247D01*
X5596Y-63405D01*
G01X1857480Y-40945D02*
G02X1849606Y-48819I-7874J0D01*
G01X7874D01*
G02X0Y-40945I0J7874D01*
G01Y30630D01*
G02X7874Y38504I7874J0D01*
G01X35835D01*
G02X43709Y30630I0J-7874D01*
G01Y-3937D01*
G03X51583Y-11811I7874J0D01*
G01X321661D01*
G03X329535Y-3937I0J7874D01*
G01Y30630D01*
G02X337409Y38504I7874J0D01*
G01X480717D01*
G02X488591Y30630I0J-7874D01*
G01Y16850D01*
G03X496465Y8976I7874J0D01*
G01X766543D01*
G03X774417Y16850I0J7874D01*
G01Y30630D01*
G02X782291Y38504I7874J0D01*
G01X879134D01*
G03X887008Y46378I0J7874D01*
G01X61000Y-48819D02*
X7874D01*
G02X0Y-40945I0J7874D01*
G01D02*
Y-25197D01*
G01X51583Y1969D02*
G03X53551Y0I1968J-1D01*
G01X319693D01*
G03X321661Y1969I0J1968D01*
G01Y38504D01*
G02X329535Y46378I7874J0D01*
G01X488591D01*
G02X496465Y38504I0J-7874D01*
G01Y22756D01*
G03X498433Y20787I1968J-1D01*
G01X764575D01*
G03X766543Y22756I0J1968D01*
G01Y38504D01*
G02X774417Y46378I7874J0D01*
G01X871260D01*
G03X879134Y54252I0J7874D01*
G01Y131004D01*
G02X887008Y138878I7874J0D01*
G01X1011024D01*
G02X1018898Y131004I0J-7874D01*
G01Y54252D01*
G03X1026772Y46378I7874J0D01*
G01X1518118D01*
G02X1525992Y38504I0J-7874D01*
G01Y1969D01*
G03X1527961Y0I1969J0D01*
G01X1794102D01*
G03X1796071Y1969I0J1969D01*
G01Y38504D01*
G02X1803945Y46378I7874J0D01*
G01X1849606D01*
G03X1857480Y54252I0J7874D01*
G01Y305794D01*
G03X1855174Y311361I-7873J0D01*
G01X1846007Y320528D01*
G02X1843701Y326096I5568J5568D01*
G01Y1593983D01*
G03X1841395Y1599550I-7873J0D01*
G01X1834196Y1606749D01*
G02X1831890Y1612317I5568J5568D01*
G01Y1732244D01*
G03X1824016Y1740118I-7874J0D01*
G01X1091777D01*
G03X1089809Y1738150I0J-1968D01*
G01Y1736654D01*
G02X1087854Y1734921I-1955J236D01*
G01X769705D01*
G02X767750Y1736654I0J1969D01*
G01Y1738150D01*
G03X765782Y1740118I-1968J0D01*
G01X33465D01*
G03X25591Y1732244I0J-7874D01*
G01Y1612317D01*
G02X23284Y1606749I-7875J1D01*
G01X10180Y1593645D01*
G03X7874Y1588077I5568J-5568D01*
G01Y320191D01*
G02X5568Y314623I-7874J0D01*
G01X2306Y311361D01*
G03X0Y305794I5567J-5567D01*
G01Y54252D01*
G03X7874Y46378I7874J0D01*
G01X43709D01*
G02X51583Y38504I0J-7874D01*
G01Y1969D01*
G01X12139Y46378D02*
G02Y38504I0J-3937D01*
G01X118813Y1747992D02*
X7874D01*
G02X0Y1755866I0J7874D01*
G01Y1815072D01*
G02X7874Y1822946I7874J0D01*
G01X1849606D01*
G02X1857480Y1815072I0J-7874D01*
G01Y1755866D01*
G02X1849606Y1747992I-7874J0D01*
G01X1709976D01*
G01X51000Y1822946D02*
X7874D01*
G03X0Y1815072I0J-7874D01*
G01Y1799324D01*
G01Y1832946D02*
Y1872946D01*
G01Y1832789D02*
Y1918261D01*
G01X993062Y1862946D02*
X0D01*
G01X7000Y1864446D02*
X0Y1862946D01*
X7000Y1861446D01*
Y1864446D01*
G01X31825Y46378D02*
G03Y38504I0J-3937D01*
G01X383371Y1747992D02*
G02X375497Y1755866I0J7874D01*
G01Y1783576D01*
G03X367623Y1791450I-7874J0D01*
G01X217811D01*
G03X209937Y1783576I0J-7874D01*
G01Y1755866D01*
G02X202063Y1747992I-7874J0D01*
G01X70690D01*
G01X92838D02*
G02Y1740118I0J-3937D01*
G01Y1747992D02*
G02Y1740118I0J-3937D01*
G01X112523Y1747992D02*
G03Y1740118I0J-3937D01*
G01Y1747992D02*
G03Y1740118I0J-3937D01*
G01X188650Y-464479D02*
Y-539479D01*
G01Y-514479D02*
X291650D01*
Y-489479D01*
G01X188650D02*
X291650D01*
G01Y-464479D02*
Y-539479D01*
G01X293650Y-464479D02*
Y-539479D01*
G01X299157Y-524479D02*
Y-519479D01*
X300423D01*
X300930Y-519729D01*
X301310Y-520062D01*
X301627Y-520562D01*
X301880Y-521146D01*
X301943Y-521979D01*
X301880Y-522812D01*
X301627Y-523396D01*
X301310Y-523896D01*
X300930Y-524229D01*
X300423Y-524479D01*
X299157D01*
G01X304067D02*
X305650Y-519479D01*
X307233Y-524479D01*
G01X306663Y-522729D02*
X304637D01*
G01X310750Y-519479D02*
Y-524479D01*
G01X309293Y-519479D02*
X312207D01*
G01X317117Y-524479D02*
X314583D01*
Y-519479D01*
X317117D01*
G01X316103Y-521896D02*
X314583D01*
G01X320950Y-524646D02*
X320823Y-524562D01*
Y-524396D01*
X320950Y-524312D01*
X321077Y-524396D01*
Y-524562D01*
X320950Y-524646D01*
G01Y-522396D02*
X320823Y-522312D01*
Y-522146D01*
X320950Y-522062D01*
X321077Y-522146D01*
Y-522312D01*
X320950Y-522396D01*
G01X299283Y-499479D02*
Y-494479D01*
X300803D01*
X301310Y-494729D01*
X301690Y-495312D01*
X301817Y-495979D01*
X301690Y-496646D01*
X301373Y-497146D01*
X300803Y-497396D01*
X299283D01*
G01X304510Y-499646D02*
X306790Y-494479D01*
G01X309293Y-499479D02*
Y-494479D01*
X312207Y-499479D01*
Y-494479D01*
G01X315850Y-499646D02*
X315723Y-499562D01*
Y-499396D01*
X315850Y-499312D01*
X315977Y-499396D01*
Y-499562D01*
X315850Y-499646D01*
G01Y-497396D02*
X315723Y-497312D01*
Y-497146D01*
X315850Y-497062D01*
X315977Y-497146D01*
Y-497312D01*
X315850Y-497396D01*
G01X293650Y-514479D02*
X493650D01*
G01X293650Y-489479D02*
X493650D01*
G01X299283Y-474479D02*
Y-469479D01*
X300803D01*
X301310Y-469729D01*
X301690Y-470312D01*
X301817Y-470979D01*
X301690Y-471646D01*
X301373Y-472146D01*
X300803Y-472396D01*
X299283D01*
G01X304383Y-474479D02*
Y-469479D01*
X305967D01*
X306473Y-469729D01*
X306790Y-470062D01*
X306917Y-470729D01*
X306790Y-471396D01*
X306410Y-471812D01*
X305967Y-472062D01*
X304383D01*
G01X305967D02*
X306917Y-474479D01*
G01X310750D02*
X310243Y-474396D01*
X309800Y-474062D01*
X309420Y-473562D01*
X309167Y-472979D01*
X309040Y-472312D01*
Y-471646D01*
X309167Y-470979D01*
X309420Y-470396D01*
X309800Y-469896D01*
X310243Y-469562D01*
X310750Y-469479D01*
X311257Y-469562D01*
X311700Y-469896D01*
X312080Y-470396D01*
X312333Y-470979D01*
X312460Y-471646D01*
Y-472312D01*
X312333Y-472979D01*
X312080Y-473562D01*
X311700Y-474062D01*
X311257Y-474396D01*
X310750Y-474479D01*
G01X314583Y-473479D02*
X314900Y-473979D01*
X315280Y-474312D01*
X315723Y-474479D01*
X316230Y-474312D01*
X316610Y-473979D01*
X316990Y-473479D01*
X317117Y-472812D01*
Y-469479D01*
G01X322217Y-474479D02*
X319683D01*
Y-469479D01*
X322217D01*
G01X321203Y-471896D02*
X319683D01*
G01X327443Y-469896D02*
X327063Y-469646D01*
X326620Y-469479D01*
X326113D01*
X325543Y-469729D01*
X325100Y-470146D01*
X324783Y-470646D01*
X324530Y-471479D01*
X324467Y-472229D01*
X324593Y-472979D01*
X324783Y-473479D01*
X325163Y-473979D01*
X325607Y-474312D01*
X326050Y-474479D01*
X326493D01*
X326937Y-474312D01*
X327317Y-474062D01*
X327633Y-473729D01*
G01X331150Y-469479D02*
Y-474479D01*
G01X329693Y-469479D02*
X332607D01*
G01X336250Y-474646D02*
X336123Y-474562D01*
Y-474396D01*
X336250Y-474312D01*
X336377Y-474396D01*
Y-474562D01*
X336250Y-474646D01*
G01Y-472396D02*
X336123Y-472312D01*
Y-472146D01*
X336250Y-472062D01*
X336377Y-472146D01*
Y-472312D01*
X336250Y-472396D01*
G01X382395Y46378D02*
G02Y38504I0J-3937D01*
G01X481984Y1791450D02*
X426865D01*
G03X418991Y1783576I0J-7874D01*
G01Y1755866D01*
G02X411117Y1747992I-7874J0D01*
G01X383371D01*
G01X402081Y46378D02*
G03Y38504I0J-3937D01*
G01X391331Y1747992D02*
G02Y1740118I0J-3937D01*
G01X408650Y-514479D02*
Y-539479D01*
G01X411283Y-516979D02*
Y-521979D01*
X413817D01*
G01X416890Y-516979D02*
X418410D01*
G01X417650D02*
Y-521979D01*
G01X416890D02*
X418410D01*
G01X423257Y-519312D02*
X423510Y-519062D01*
X423700Y-518646D01*
X423827Y-518062D01*
X423700Y-517562D01*
X423447Y-517229D01*
X423003Y-516979D01*
X421293D01*
Y-521979D01*
X423383D01*
X423827Y-521646D01*
X424080Y-521146D01*
X424207Y-520562D01*
X424080Y-519979D01*
X423700Y-519479D01*
X423257Y-519312D01*
X421293D01*
G01X427850Y-522146D02*
X427723Y-522062D01*
Y-521896D01*
X427850Y-521812D01*
X427977Y-521896D01*
Y-522062D01*
X427850Y-522146D01*
G01Y-519896D02*
X427723Y-519812D01*
Y-519646D01*
X427850Y-519562D01*
X427977Y-519646D01*
Y-519812D01*
X427850Y-519896D01*
G01X411016Y1747992D02*
G03Y1740118I0J-3937D01*
G01X451650Y-514479D02*
Y-539479D01*
G01Y-489479D02*
Y-514479D01*
G01X456663Y-541646D02*
X456770Y-541521D01*
X456850Y-541312D01*
X456903Y-541021D01*
X456850Y-540771D01*
X456743Y-540604D01*
X456557Y-540479D01*
X455837D01*
Y-542979D01*
X456717D01*
X456903Y-542812D01*
X457010Y-542562D01*
X457063Y-542271D01*
X457010Y-541979D01*
X456850Y-541729D01*
X456663Y-541646D01*
X455837D01*
G01X459130Y-542979D02*
Y-541312D01*
G01Y-541604D02*
X459023Y-541437D01*
X458863Y-541354D01*
X458677Y-541312D01*
X458490Y-541396D01*
X458330Y-541562D01*
X458223Y-541812D01*
X458170Y-542146D01*
X458223Y-542479D01*
X458330Y-542729D01*
X458490Y-542896D01*
X458677Y-542979D01*
X458863Y-542937D01*
X459023Y-542812D01*
X459130Y-542646D01*
G01X460450Y-542687D02*
X460583Y-542854D01*
X460770Y-542979D01*
X460930D01*
X461090Y-542896D01*
X461197Y-542771D01*
X461250Y-542604D01*
X461223Y-542354D01*
X461117Y-542229D01*
X460637Y-541979D01*
X460530Y-541687D01*
X460583Y-541479D01*
X460690Y-541354D01*
X460850Y-541312D01*
X461010Y-541354D01*
X461170Y-541479D01*
G01X462650Y-541854D02*
X463503D01*
X463423Y-541562D01*
X463290Y-541396D01*
X463103Y-541312D01*
X462917Y-541354D01*
X462757Y-541479D01*
X462650Y-541771D01*
X462597Y-542021D01*
Y-542271D01*
X462650Y-542521D01*
X462783Y-542771D01*
X462943Y-542937D01*
X463130Y-542979D01*
X463317Y-542896D01*
X463503Y-542646D01*
G01X464770Y-542979D02*
Y-540479D01*
G01Y-541729D02*
X464903Y-541479D01*
X465063Y-541354D01*
X465223Y-541312D01*
X465463Y-541396D01*
X465623Y-541562D01*
X465730Y-541854D01*
Y-542187D01*
X465677Y-542521D01*
X465570Y-542771D01*
X465383Y-542937D01*
X465223Y-542979D01*
X465063Y-542937D01*
X464903Y-542812D01*
X464770Y-542604D01*
G01X467450Y-542979D02*
X467290Y-542937D01*
X467130Y-542771D01*
X467023Y-542479D01*
X466970Y-542146D01*
X467023Y-541812D01*
X467130Y-541521D01*
X467290Y-541354D01*
X467450Y-541312D01*
X467610Y-541354D01*
X467770Y-541521D01*
X467877Y-541812D01*
X467903Y-542146D01*
X467877Y-542479D01*
X467770Y-542771D01*
X467610Y-542937D01*
X467450Y-542979D01*
G01X470130D02*
Y-541312D01*
G01Y-541604D02*
X470023Y-541437D01*
X469863Y-541354D01*
X469677Y-541312D01*
X469490Y-541396D01*
X469330Y-541562D01*
X469223Y-541812D01*
X469170Y-542146D01*
X469223Y-542479D01*
X469330Y-542729D01*
X469490Y-542896D01*
X469677Y-542979D01*
X469863Y-542937D01*
X470023Y-542812D01*
X470130Y-542646D01*
G01X471477Y-542979D02*
Y-541312D01*
G01Y-541646D02*
X471610Y-541479D01*
X471743Y-541354D01*
X471930Y-541312D01*
X472063Y-541354D01*
X472223Y-541479D01*
G01X474530Y-540479D02*
Y-542979D01*
G01Y-542604D02*
X474423Y-542812D01*
X474263Y-542937D01*
X474077Y-542979D01*
X473863Y-542896D01*
X473703Y-542687D01*
X473597Y-542437D01*
X473570Y-542146D01*
X473597Y-541854D01*
X473703Y-541604D01*
X473863Y-541396D01*
X474077Y-541312D01*
X474263Y-541354D01*
X474397Y-541437D01*
X474530Y-541604D01*
G01X477917Y-542979D02*
Y-540479D01*
X478583D01*
X478797Y-540604D01*
X478930Y-540771D01*
X478983Y-541104D01*
X478930Y-541437D01*
X478770Y-541646D01*
X478583Y-541771D01*
X477917D01*
G01X478583D02*
X478983Y-542979D01*
G01X480250Y-541854D02*
X481103D01*
X481023Y-541562D01*
X480890Y-541396D01*
X480703Y-541312D01*
X480517Y-541354D01*
X480357Y-541479D01*
X480250Y-541771D01*
X480197Y-542021D01*
Y-542271D01*
X480250Y-542521D01*
X480383Y-542771D01*
X480543Y-542937D01*
X480730Y-542979D01*
X480917Y-542896D01*
X481103Y-542646D01*
G01X482370Y-541312D02*
X482850Y-542979D01*
X483330Y-541312D01*
G01X485050Y-543062D02*
X484997Y-543021D01*
Y-542937D01*
X485050Y-542896D01*
X485103Y-542937D01*
Y-543021D01*
X485050Y-543062D01*
G01X487250Y-542979D02*
X487437Y-542937D01*
X487650Y-542812D01*
X487783Y-542604D01*
X487837Y-542312D01*
X487783Y-542021D01*
X487623Y-541771D01*
X487383Y-541646D01*
X487117D01*
X486957Y-541562D01*
X486823Y-541354D01*
X486770Y-541062D01*
X486850Y-540771D01*
X487037Y-540562D01*
X487250Y-540479D01*
X487463Y-540562D01*
X487650Y-540771D01*
X487730Y-541062D01*
X487677Y-541354D01*
X487543Y-541562D01*
X487383Y-541646D01*
X487117D01*
X486877Y-541771D01*
X486717Y-542021D01*
X486663Y-542312D01*
X486717Y-542604D01*
X486850Y-542812D01*
X487063Y-542937D01*
X487250Y-542979D01*
G01X489663Y-541646D02*
X489770Y-541521D01*
X489850Y-541312D01*
X489903Y-541021D01*
X489850Y-540771D01*
X489743Y-540604D01*
X489557Y-540479D01*
X488837D01*
Y-542979D01*
X489717D01*
X489903Y-542812D01*
X490010Y-542562D01*
X490063Y-542271D01*
X490010Y-541979D01*
X489850Y-541729D01*
X489663Y-541646D01*
X488837D01*
G01X455550Y-516979D02*
Y-521979D01*
G01X454093Y-516979D02*
X457007D01*
G01X460650Y-521979D02*
X460270Y-521896D01*
X459890Y-521562D01*
X459637Y-520979D01*
X459510Y-520312D01*
X459637Y-519646D01*
X459890Y-519062D01*
X460270Y-518729D01*
X460650Y-518646D01*
X461030Y-518729D01*
X461410Y-519062D01*
X461663Y-519646D01*
X461727Y-520312D01*
X461663Y-520979D01*
X461410Y-521562D01*
X461030Y-521896D01*
X460650Y-521979D01*
G01X465750D02*
X465370Y-521896D01*
X464990Y-521562D01*
X464737Y-520979D01*
X464610Y-520312D01*
X464737Y-519646D01*
X464990Y-519062D01*
X465370Y-518729D01*
X465750Y-518646D01*
X466130Y-518729D01*
X466510Y-519062D01*
X466763Y-519646D01*
X466827Y-520312D01*
X466763Y-520979D01*
X466510Y-521562D01*
X466130Y-521896D01*
X465750Y-521979D01*
G01X470850D02*
Y-516979D01*
G01X475950Y-522146D02*
X475823Y-522062D01*
Y-521896D01*
X475950Y-521812D01*
X476077Y-521896D01*
Y-522062D01*
X475950Y-522146D01*
G01Y-519896D02*
X475823Y-519812D01*
Y-519646D01*
X475950Y-519562D01*
X476077Y-519646D01*
Y-519812D01*
X475950Y-519896D01*
G01X454283Y-496979D02*
Y-491979D01*
X455867D01*
X456373Y-492229D01*
X456690Y-492562D01*
X456817Y-493229D01*
X456690Y-493896D01*
X456310Y-494312D01*
X455867Y-494562D01*
X454283D01*
G01X455867D02*
X456817Y-496979D01*
G01X461917D02*
X459383D01*
Y-491979D01*
X461917D01*
G01X460903Y-494396D02*
X459383D01*
G01X464167Y-491979D02*
X465750Y-496979D01*
X467333Y-491979D01*
G01X470850Y-497146D02*
X470723Y-497062D01*
Y-496896D01*
X470850Y-496812D01*
X470977Y-496896D01*
Y-497062D01*
X470850Y-497146D01*
G01Y-494896D02*
X470723Y-494812D01*
Y-494646D01*
X470850Y-494562D01*
X470977Y-494646D01*
Y-494812D01*
X470850Y-494896D01*
G01X1375497Y1791450D02*
X1225685D01*
G03X1217811Y1783576I0J-7874D01*
G01Y1755866D01*
G02X1209937Y1747992I-7874J0D01*
G01X1097210D01*
G02X1089336Y1755866I0J7874D01*
G01Y1783576D01*
G03X1081462Y1791450I-7874J0D01*
G01X776098D01*
G03X768224Y1783576I0J-7874D01*
G01Y1755866D01*
G02X760350Y1747992I-7874J0D01*
G01X647544D01*
G02X639670Y1755866I0J7874D01*
G01Y1783576D01*
G03X631796Y1791450I-7874J0D01*
G01X481984D01*
G01X1289590Y1361034D02*
X689590D01*
Y461034D01*
G01Y967660D02*
X1289590D01*
G01X727896Y1747992D02*
G02Y1740118I0J-3937D01*
G01Y1747992D02*
G02Y1740118I0J-3937D01*
G01X747581Y1747992D02*
G03Y1740118I0J-3937D01*
G01Y1747992D02*
G03Y1740118I0J-3937D01*
G01X789269Y46378D02*
G02Y38504I0J-3937D01*
G01X808955Y46378D02*
G03Y38504I0J-3937D01*
G01X887008Y127067D02*
Y46378D01*
G01X879134Y69362D02*
G02X887008I3937J0D01*
G01X879134Y89048D02*
G03X887008I3937J0D01*
G01Y127067D02*
G02X890945Y131004I3937J0D01*
G01X1007087D02*
X890945D01*
G01X903689Y138878D02*
G02Y131004I0J-3937D01*
G01X923375Y138878D02*
G03Y131004I0J-3937D01*
G01X1011024Y46378D02*
Y127067D01*
G01Y46378D02*
G03X1018898Y38504I7874J0D01*
G01X1510244D01*
G02X1518118Y30630I0J-7874D01*
G01Y-3937D01*
G03X1525992Y-11811I7874J0D01*
G01X1796071D01*
G03X1803945Y-3937I0J7874D01*
G01Y30630D01*
G02X1811819Y38504I7874J0D01*
G01X1849606D01*
G02X1857480Y30630I0J-7874D01*
G01Y-40945D01*
G01X1007087Y131004D02*
G02X1011024Y127067I0J-3937D01*
G01X1016837Y1844196D02*
X1012187D01*
Y1856696D01*
X1016837D01*
G01X1035702Y46378D02*
G02Y38504I0J-3937D01*
G01X1055388Y46378D02*
G03Y38504I0J-3937D01*
G01X1085037Y1844196D02*
X1089687D01*
Y1856696D01*
X1085037D01*
G01X1101025Y1747992D02*
G02Y1740118I0J-3937D01*
G01Y1747992D02*
G02Y1740118I0J-3937D01*
G01X1120710Y1747992D02*
G03Y1740118I0J-3937D01*
G01Y1747992D02*
G03Y1740118I0J-3937D01*
G01X1108512Y1862946D02*
X2101574D01*
G01X1188739Y1747992D02*
G02Y1740118I0J-3937D01*
G01Y1747992D02*
G02Y1740118I0J-3937D01*
G01X1208424Y1747992D02*
G03Y1740118I0J-3937D01*
G01Y1747992D02*
G03Y1740118I0J-3937D01*
G01X1352496Y46378D02*
G02Y38504I0J-3937D01*
G01X1372182Y46378D02*
G03Y38504I0J-3937D01*
G01X1754370Y1747992D02*
X1655418D01*
G02X1647544Y1755866I0J7874D01*
G01Y1783576D01*
G03X1639670Y1791450I-7874J0D01*
G01X1489858D01*
G03X1481984Y1783576I0J-7874D01*
G01Y1755866D01*
G02X1474110Y1747992I-7874J0D01*
G01X1446363D01*
G02X1438489Y1755866I0J7874D01*
G01Y1783576D01*
G03X1430615Y1791450I-7874J0D01*
G01X1375497D01*
G01X1450715Y1747992D02*
G02Y1740118I0J-3937D01*
G01X1473813Y46378D02*
G02Y38504I0J-3937D01*
G01X1470400Y1747992D02*
G03Y1740118I0J-3937D01*
G01X1493499Y46378D02*
G03Y38504I0J-3937D01*
G01X1659152Y1747992D02*
G02Y1740118I0J-3937D01*
G01Y1747992D02*
G02Y1740118I0J-3937D01*
G01X1678837Y1747992D02*
G03Y1740118I0J-3937D01*
G01Y1747992D02*
G03Y1740118I0J-3937D01*
G01X1751150Y1747992D02*
G02Y1740118I0J-3937D01*
G01Y1747992D02*
G02Y1740118I0J-3937D01*
G01X1770835Y1747992D02*
G03Y1740118I0J-3937D01*
G01Y1747992D02*
G03Y1740118I0J-3937D01*
G01X1778480Y1822946D02*
X1849606D01*
G02X1857480Y1815072I0J-7874D01*
G01Y1799324D01*
G01Y-25197D02*
Y-40945D01*
G02X1849606Y-48819I-7874J0D01*
G01X1808480D01*
G01X1818974Y46378D02*
G02Y38504I0J-3937D01*
G01X1831890Y1640193D02*
G02X1839764I3937J0D01*
G01X1831890D02*
G02X1839764I3937J0D01*
G01X1831890Y1659878D02*
G03X1839764I3937J0D01*
G01X1831890D02*
G03X1839764I3937J0D01*
G01X1831890D02*
G03X1839764I3937J0D01*
G01X1838660Y46378D02*
G03Y38504I0J-3937D01*
G01X1843701Y415239D02*
G02X1851575I3937J0D01*
G01X1843701D02*
G02X1851575I3937J0D01*
G01X1843701Y434924D02*
G03X1851575I3937J0D01*
G01X1843701D02*
G03X1851575I3937J0D01*
G01X1843701Y554634D02*
G02X1851575I3937J0D01*
G01X1843701D02*
G02X1851575I3937J0D01*
G01X1843701Y574319D02*
G03X1851575I3937J0D01*
G01X1843701D02*
G03X1851575I3937J0D01*
G01X1843701Y768284D02*
G02X1851575I3937J0D01*
G01X1843701D02*
G02X1851575I3937J0D01*
G01X1843701Y787969D02*
G03X1851575I3937J0D01*
G01X1843701D02*
G03X1851575I3937J0D01*
G01X1843701Y983300D02*
G02X1851575I3937J0D01*
G01X1843701D02*
G02X1851575I3937J0D01*
G01X1843701Y1002985D02*
G03X1851575I3937J0D01*
G01X1843701D02*
G03X1851575I3937J0D01*
G01X1843701Y1242960D02*
G02X1851575I3937J0D01*
G01X1843701D02*
G02X1851575I3937J0D01*
G01X1843701Y1262645D02*
G03X1851575I3937J0D01*
G01X1843701D02*
G03X1851575I3937J0D01*
G01X1843701Y1466175D02*
G02X1851575I3937J0D01*
G01X1843701D02*
G02X1851575I3937J0D01*
G01X1843701Y1485860D02*
G03X1851575I3937J0D01*
G01X1843701D02*
G03X1851575I3937J0D01*
G01X2040574Y1822946D02*
X1873228D01*
G03X1865354Y1815072I0J-7874D01*
G01Y1747992D01*
G02X1857480Y1740118I-7874J0D01*
G01X1847638D01*
G03X1839764Y1732244I0J-7874D01*
G01Y1615579D01*
G03X1842070Y1610011I7874J0D01*
G01X1846963Y1605118D01*
G02X1851575Y1593983I-11134J-11134D01*
G01Y329357D01*
G03X1853882Y323789I7874J0D01*
G01X1860742Y316929D01*
G02X1865354Y305794I-11134J-11134D01*
G01Y-40945D01*
G03X1873228Y-48819I7874J0D01*
G01X2093700D01*
G03X2101574Y-40945I0J7874D01*
G01Y126550D01*
G01X1857480Y-13311D02*
G02X1865354I3937J0D01*
G01X1857480Y6375D02*
G03X1865354I3937J0D01*
G01X1857480Y193845D02*
G02X1865354I3937J0D01*
G01X1857480D02*
G02X1865354I3937J0D01*
G01X1857480Y213530D02*
G03X1865354I3937J0D01*
G01X1857480D02*
G03X1865354I3937J0D01*
G01X1857480Y1775788D02*
G02X1865354I3937J0D01*
G01X1857480Y1795474D02*
G03X1865354I3937J0D01*
G01X1857480Y1832789D02*
Y1872576D01*
G01X2023700Y1229954D02*
G03X2031574Y1222080I7874J0D01*
G01X2101574Y1791450D02*
G02X2093700Y1783576I-7874J0D01*
G01X2031574D01*
G03X2023700Y1775702I0J-7874D01*
G01Y1229954D01*
G01X2026456Y1318677D02*
G03I-1575J0D01*
G01X2031574Y1310803D02*
G03X2023700I-3937J0D01*
G01X2026456Y1334425D02*
G03I-1575J0D01*
G01Y1326551D02*
G03I-1575J0D01*
G01Y1342299D02*
G03I-1575J0D01*
G01X2031574Y1350173D02*
G02X2023700I-3937J0D01*
G01X2031574Y1610803D02*
G03X2023700I-3937J0D01*
G01X2026456Y1618677D02*
G03I-1575J0D01*
G01Y1626551D02*
G03I-1575J0D01*
G01Y1642299D02*
G03I-1575J0D01*
G01Y1634425D02*
G03I-1575J0D01*
G01X2031574Y1650173D02*
G02X2023700I-3937J0D01*
G01X2022574Y1822946D02*
X2093700D01*
G02X2101574Y1815072I0J-7874D01*
G01Y1799324D01*
G01X2031574Y1222080D02*
X2093700D01*
G01X2031574Y1237828D02*
G03X2039448Y1229954I7874J0D01*
G01X2093700D01*
G03X2101574Y1237828I0J7874D01*
G01D02*
X2031574D01*
G01D02*
Y1767828D01*
X2101574D01*
Y1237828D01*
G01X2101772Y1702606D02*
X2031772D01*
G01X2031574Y1767828D02*
G02X2039448Y1775702I7874J0D01*
G01X2093700D01*
G02X2101574Y1767828I0J-7874D01*
G01X2093700Y1822946D02*
X2040574D01*
G01X2101574Y-25197D02*
Y-40945D01*
G02X2093700Y-48819I-7874J0D01*
G01X2052574D01*
G01X2056338Y1223261D02*
G03I-1575J0D01*
G01X2064212D02*
G03I-1575J0D01*
G01X2046889Y1229954D02*
G02Y1222080I0J-3937D01*
G01Y1775702D02*
G03Y1783576I0J3937D01*
G01X2056338Y1782395D02*
G03I-1575J0D01*
G01X2064212D02*
G03I-1575J0D01*
G01X2079960Y1223261D02*
G03I-1575J0D01*
G01X2072086D02*
G03I-1575J0D01*
G01X2079960Y1782395D02*
G03I-1575J0D01*
G01X2072086D02*
G03I-1575J0D01*
G01X2101574Y1159083D02*
Y1214206D01*
G03X2093700Y1222080I-7874J0D01*
G01X2086259Y1229954D02*
G03Y1222080I0J-3937D01*
G01Y1775702D02*
G02Y1783576I0J3937D01*
G01X2101574Y1815072D02*
G03X2093700Y1822946I-7874J0D01*
G01X2094574Y1861446D02*
X2101574Y1862946D01*
X2094574Y1864446D01*
Y1861446D01*
G01X2101574Y44466D02*
Y-26660D01*
G01Y82156D02*
Y1211966D01*
G01Y1815072D02*
Y1791450D01*
G01Y1803846D02*
Y1815072D01*
G01Y1832946D02*
Y1872946D01*
G01Y1832789D02*
Y1872576D01*
G01X2111574Y-48819D02*
X2151574D01*
G01X2111574Y1822946D02*
X2151574D01*
G01X2141574Y829339D02*
Y-48819D01*
G01X2140074Y-41819D02*
X2141574Y-48819D01*
X2143074Y-41819D01*
X2140074D01*
G01X2141574Y944789D02*
Y1822946D01*
G01X2143074Y1815946D02*
X2141574Y1822946D01*
X2140074Y1815946D01*
X2143074D01*
G01X2160324Y846914D02*
Y842264D01*
X2147824D01*
Y846914D01*
G01X2160324Y927514D02*
Y932164D01*
X2147824D01*
Y927514D01*
G01X2449315Y44769D02*
X2449568Y45019D01*
X2449758Y45435D01*
X2449885Y46019D01*
X2449758Y46519D01*
X2449505Y46852D01*
X2449061Y47102D01*
X2447351D01*
Y42102D01*
X2449441D01*
X2449885Y42435D01*
X2450138Y42935D01*
X2450265Y43519D01*
X2450138Y44102D01*
X2449758Y44602D01*
X2449315Y44769D01*
X2447351D01*
G01X2453021Y42102D02*
Y45435D01*
G01Y44769D02*
X2453338Y45102D01*
X2453655Y45352D01*
X2454098Y45435D01*
X2454415Y45352D01*
X2454795Y45102D01*
G01X2458058Y44352D02*
X2460085D01*
X2459895Y44935D01*
X2459578Y45269D01*
X2459135Y45435D01*
X2458691Y45352D01*
X2458311Y45102D01*
X2458058Y44519D01*
X2457931Y44019D01*
Y43519D01*
X2458058Y43019D01*
X2458375Y42519D01*
X2458755Y42185D01*
X2459198Y42102D01*
X2459641Y42269D01*
X2460085Y42769D01*
G01X2465248Y42102D02*
Y45435D01*
G01Y44852D02*
X2464995Y45185D01*
X2464615Y45352D01*
X2464171Y45435D01*
X2463728Y45269D01*
X2463348Y44935D01*
X2463095Y44435D01*
X2462968Y43769D01*
X2463095Y43102D01*
X2463348Y42602D01*
X2463728Y42269D01*
X2464171Y42102D01*
X2464615Y42185D01*
X2464995Y42435D01*
X2465248Y42769D01*
G01X2468131Y42102D02*
Y47102D01*
G01X2470158Y45435D02*
X2468131Y43519D01*
G01X2468955Y44269D02*
X2470285Y42102D01*
G01X2474308Y47102D02*
Y42102D01*
G01X2473421Y45435D02*
X2475195D01*
G01X2480548Y42102D02*
Y45435D01*
G01Y44852D02*
X2480295Y45185D01*
X2479915Y45352D01*
X2479471Y45435D01*
X2479028Y45269D01*
X2478648Y44935D01*
X2478395Y44435D01*
X2478268Y43769D01*
X2478395Y43102D01*
X2478648Y42602D01*
X2479028Y42269D01*
X2479471Y42102D01*
X2479915Y42185D01*
X2480295Y42435D01*
X2480548Y42769D01*
G01X2483368Y42102D02*
Y47102D01*
G01Y44602D02*
X2483685Y45102D01*
X2484065Y45352D01*
X2484445Y45435D01*
X2485015Y45269D01*
X2485395Y44935D01*
X2485648Y44352D01*
Y43685D01*
X2485521Y43019D01*
X2485268Y42519D01*
X2484825Y42185D01*
X2484445Y42102D01*
X2484065Y42185D01*
X2483685Y42435D01*
X2483368Y42852D01*
G01X2489608Y41935D02*
X2489481Y42019D01*
Y42185D01*
X2489608Y42269D01*
X2489735Y42185D01*
Y42019D01*
X2489608Y41935D01*
G01Y44185D02*
X2489481Y44269D01*
Y44435D01*
X2489608Y44519D01*
X2489735Y44435D01*
Y44269D01*
X2489608Y44185D01*
G01X2524105Y108632D02*
Y113632D01*
X2526511D01*
G01X2525625Y111215D02*
X2524105D01*
G01X2530408Y108632D02*
X2530028Y108715D01*
X2529648Y109049D01*
X2529395Y109632D01*
X2529268Y110299D01*
X2529395Y110965D01*
X2529648Y111549D01*
X2530028Y111882D01*
X2530408Y111965D01*
X2530788Y111882D01*
X2531168Y111549D01*
X2531421Y110965D01*
X2531485Y110299D01*
X2531421Y109632D01*
X2531168Y109049D01*
X2530788Y108715D01*
X2530408Y108632D01*
G01X2534621D02*
Y111965D01*
G01Y111299D02*
X2534938Y111632D01*
X2535255Y111882D01*
X2535698Y111965D01*
X2536015Y111882D01*
X2536395Y111632D01*
G01X2544441Y108632D02*
Y113632D01*
X2545961D01*
X2546468Y113382D01*
X2546848Y112799D01*
X2546975Y112132D01*
X2546848Y111465D01*
X2546531Y110965D01*
X2545961Y110715D01*
X2544441D01*
G01X2551948Y108632D02*
Y111965D01*
G01Y111382D02*
X2551695Y111715D01*
X2551315Y111882D01*
X2550871Y111965D01*
X2550428Y111799D01*
X2550048Y111465D01*
X2549795Y110965D01*
X2549668Y110299D01*
X2549795Y109632D01*
X2550048Y109132D01*
X2550428Y108799D01*
X2550871Y108632D01*
X2551315Y108715D01*
X2551695Y108965D01*
X2551948Y109299D01*
G01X2554831Y108632D02*
Y111965D01*
G01Y111132D02*
X2555085Y111549D01*
X2555465Y111882D01*
X2555971Y111965D01*
X2556415Y111882D01*
X2556795Y111549D01*
X2556985Y110965D01*
Y108632D01*
G01X2560058Y110882D02*
X2562085D01*
X2561895Y111465D01*
X2561578Y111799D01*
X2561135Y111965D01*
X2560691Y111882D01*
X2560311Y111632D01*
X2560058Y111049D01*
X2559931Y110549D01*
Y110049D01*
X2560058Y109549D01*
X2560375Y109049D01*
X2560755Y108715D01*
X2561198Y108632D01*
X2561641Y108799D01*
X2562085Y109299D01*
G01X2566108Y108632D02*
Y113632D01*
G01X2576815Y111299D02*
X2577068Y111549D01*
X2577258Y111965D01*
X2577385Y112549D01*
X2577258Y113049D01*
X2577005Y113382D01*
X2576561Y113632D01*
X2574851D01*
Y108632D01*
X2576941D01*
X2577385Y108965D01*
X2577638Y109465D01*
X2577765Y110049D01*
X2577638Y110632D01*
X2577258Y111132D01*
X2576815Y111299D01*
X2574851D01*
G01X2581408Y108632D02*
X2581028Y108715D01*
X2580648Y109049D01*
X2580395Y109632D01*
X2580268Y110299D01*
X2580395Y110965D01*
X2580648Y111549D01*
X2581028Y111882D01*
X2581408Y111965D01*
X2581788Y111882D01*
X2582168Y111549D01*
X2582421Y110965D01*
X2582485Y110299D01*
X2582421Y109632D01*
X2582168Y109049D01*
X2581788Y108715D01*
X2581408Y108632D01*
G01X2587648D02*
Y111965D01*
G01Y111382D02*
X2587395Y111715D01*
X2587015Y111882D01*
X2586571Y111965D01*
X2586128Y111799D01*
X2585748Y111465D01*
X2585495Y110965D01*
X2585368Y110299D01*
X2585495Y109632D01*
X2585748Y109132D01*
X2586128Y108799D01*
X2586571Y108632D01*
X2587015Y108715D01*
X2587395Y108965D01*
X2587648Y109299D01*
G01X2590721Y108632D02*
Y111965D01*
G01Y111299D02*
X2591038Y111632D01*
X2591355Y111882D01*
X2591798Y111965D01*
X2592115Y111882D01*
X2592495Y111632D01*
G01X2597848Y113632D02*
Y108632D01*
G01Y109382D02*
X2597595Y108965D01*
X2597215Y108715D01*
X2596771Y108632D01*
X2596265Y108799D01*
X2595885Y109215D01*
X2595631Y109715D01*
X2595568Y110299D01*
X2595631Y110882D01*
X2595885Y111382D01*
X2596265Y111799D01*
X2596771Y111965D01*
X2597215Y111882D01*
X2597531Y111715D01*
X2597848Y111382D01*
G01X2525308Y126232D02*
Y121232D01*
G01X2523851Y126232D02*
X2526765D01*
G01X2530408Y121232D02*
X2530028Y121315D01*
X2529648Y121649D01*
X2529395Y122232D01*
X2529268Y122899D01*
X2529395Y123565D01*
X2529648Y124149D01*
X2530028Y124482D01*
X2530408Y124565D01*
X2530788Y124482D01*
X2531168Y124149D01*
X2531421Y123565D01*
X2531485Y122899D01*
X2531421Y122232D01*
X2531168Y121649D01*
X2530788Y121315D01*
X2530408Y121232D01*
G01X2534368Y119565D02*
Y124565D01*
G01Y123815D02*
X2534685Y124232D01*
X2535001Y124482D01*
X2535508Y124565D01*
X2535951Y124482D01*
X2536395Y124065D01*
X2536585Y123482D01*
X2536648Y122899D01*
X2536585Y122315D01*
X2536395Y121732D01*
X2536015Y121399D01*
X2535508Y121232D01*
X2535065Y121315D01*
X2534621Y121565D01*
X2534368Y121899D01*
G01X2544125Y121232D02*
X2545708Y126232D01*
X2547291Y121232D01*
G01X2546721Y122982D02*
X2544695D01*
G01X2549731Y121232D02*
Y124565D01*
G01Y123732D02*
X2549985Y124149D01*
X2550365Y124482D01*
X2550871Y124565D01*
X2551315Y124482D01*
X2551695Y124149D01*
X2551885Y123565D01*
Y121232D01*
G01X2557048Y126232D02*
Y121232D01*
G01Y121982D02*
X2556795Y121565D01*
X2556415Y121315D01*
X2555971Y121232D01*
X2555465Y121399D01*
X2555085Y121815D01*
X2554831Y122315D01*
X2554768Y122899D01*
X2554831Y123482D01*
X2555085Y123982D01*
X2555465Y124399D01*
X2555971Y124565D01*
X2556415Y124482D01*
X2556731Y124315D01*
X2557048Y123982D01*
G01X2566615Y123899D02*
X2566868Y124149D01*
X2567058Y124565D01*
X2567185Y125149D01*
X2567058Y125649D01*
X2566805Y125982D01*
X2566361Y126232D01*
X2564651D01*
Y121232D01*
X2566741D01*
X2567185Y121565D01*
X2567438Y122065D01*
X2567565Y122649D01*
X2567438Y123232D01*
X2567058Y123732D01*
X2566615Y123899D01*
X2564651D01*
G01X2571208Y121232D02*
X2570828Y121315D01*
X2570448Y121649D01*
X2570195Y122232D01*
X2570068Y122899D01*
X2570195Y123565D01*
X2570448Y124149D01*
X2570828Y124482D01*
X2571208Y124565D01*
X2571588Y124482D01*
X2571968Y124149D01*
X2572221Y123565D01*
X2572285Y122899D01*
X2572221Y122232D01*
X2571968Y121649D01*
X2571588Y121315D01*
X2571208Y121232D01*
G01X2576308Y126232D02*
Y121232D01*
G01X2575421Y124565D02*
X2577195D01*
G01X2581408Y126232D02*
Y121232D01*
G01X2580521Y124565D02*
X2582295D01*
G01X2586508Y121232D02*
X2586128Y121315D01*
X2585748Y121649D01*
X2585495Y122232D01*
X2585368Y122899D01*
X2585495Y123565D01*
X2585748Y124149D01*
X2586128Y124482D01*
X2586508Y124565D01*
X2586888Y124482D01*
X2587268Y124149D01*
X2587521Y123565D01*
X2587585Y122899D01*
X2587521Y122232D01*
X2587268Y121649D01*
X2586888Y121315D01*
X2586508Y121232D01*
G01X2589708D02*
Y124565D01*
G01Y123649D02*
X2589898Y124065D01*
X2590215Y124399D01*
X2590658Y124565D01*
X2591101Y124399D01*
X2591418Y124065D01*
X2591608Y123649D01*
Y121232D01*
G01Y123649D02*
X2591798Y124065D01*
X2592115Y124399D01*
X2592558Y124565D01*
X2593001Y124399D01*
X2593318Y124065D01*
X2593508Y123565D01*
Y121232D01*
G01X2600478Y121899D02*
X2600985Y121482D01*
X2601555Y121232D01*
X2602061D01*
X2602568Y121482D01*
X2602948Y121899D01*
X2603138Y122482D01*
X2603011Y123065D01*
X2602695Y123565D01*
X2602125Y123899D01*
X2601365Y124065D01*
X2600921Y124399D01*
X2600731Y124982D01*
X2600858Y125565D01*
X2601175Y125982D01*
X2601618Y126232D01*
X2602061D01*
X2602505Y126065D01*
X2602885Y125649D01*
G01X2606908Y124565D02*
Y121232D01*
G01Y125899D02*
X2606781Y125982D01*
Y126149D01*
X2606908Y126232D01*
X2607035Y126149D01*
Y125982D01*
X2606908Y125899D01*
G01X2613148Y126232D02*
Y121232D01*
G01Y121982D02*
X2612895Y121565D01*
X2612515Y121315D01*
X2612071Y121232D01*
X2611565Y121399D01*
X2611185Y121815D01*
X2610931Y122315D01*
X2610868Y122899D01*
X2610931Y123482D01*
X2611185Y123982D01*
X2611565Y124399D01*
X2612071Y124565D01*
X2612515Y124482D01*
X2612831Y124315D01*
X2613148Y123982D01*
G01X2616158Y123482D02*
X2618185D01*
X2617995Y124065D01*
X2617678Y124399D01*
X2617235Y124565D01*
X2616791Y124482D01*
X2616411Y124232D01*
X2616158Y123649D01*
X2616031Y123149D01*
Y122649D01*
X2616158Y122149D01*
X2616475Y121649D01*
X2616855Y121315D01*
X2617298Y121232D01*
X2617741Y121399D01*
X2618185Y121899D01*
G01X2524105Y108632D02*
Y113632D01*
X2526511D01*
G01X2525625Y111215D02*
X2524105D01*
G01X2530408Y108632D02*
X2530028Y108715D01*
X2529648Y109049D01*
X2529395Y109632D01*
X2529268Y110299D01*
X2529395Y110965D01*
X2529648Y111549D01*
X2530028Y111882D01*
X2530408Y111965D01*
X2530788Y111882D01*
X2531168Y111549D01*
X2531421Y110965D01*
X2531485Y110299D01*
X2531421Y109632D01*
X2531168Y109049D01*
X2530788Y108715D01*
X2530408Y108632D01*
G01X2534621D02*
Y111965D01*
G01Y111299D02*
X2534938Y111632D01*
X2535255Y111882D01*
X2535698Y111965D01*
X2536015Y111882D01*
X2536395Y111632D01*
G01X2544441Y108632D02*
Y113632D01*
X2545961D01*
X2546468Y113382D01*
X2546848Y112799D01*
X2546975Y112132D01*
X2546848Y111465D01*
X2546531Y110965D01*
X2545961Y110715D01*
X2544441D01*
G01X2551948Y108632D02*
Y111965D01*
G01Y111382D02*
X2551695Y111715D01*
X2551315Y111882D01*
X2550871Y111965D01*
X2550428Y111799D01*
X2550048Y111465D01*
X2549795Y110965D01*
X2549668Y110299D01*
X2549795Y109632D01*
X2550048Y109132D01*
X2550428Y108799D01*
X2550871Y108632D01*
X2551315Y108715D01*
X2551695Y108965D01*
X2551948Y109299D01*
G01X2554831Y108632D02*
Y111965D01*
G01Y111132D02*
X2555085Y111549D01*
X2555465Y111882D01*
X2555971Y111965D01*
X2556415Y111882D01*
X2556795Y111549D01*
X2556985Y110965D01*
Y108632D01*
G01X2560058Y110882D02*
X2562085D01*
X2561895Y111465D01*
X2561578Y111799D01*
X2561135Y111965D01*
X2560691Y111882D01*
X2560311Y111632D01*
X2560058Y111049D01*
X2559931Y110549D01*
Y110049D01*
X2560058Y109549D01*
X2560375Y109049D01*
X2560755Y108715D01*
X2561198Y108632D01*
X2561641Y108799D01*
X2562085Y109299D01*
G01X2566108Y108632D02*
Y113632D01*
G01X2576815Y111299D02*
X2577068Y111549D01*
X2577258Y111965D01*
X2577385Y112549D01*
X2577258Y113049D01*
X2577005Y113382D01*
X2576561Y113632D01*
X2574851D01*
Y108632D01*
X2576941D01*
X2577385Y108965D01*
X2577638Y109465D01*
X2577765Y110049D01*
X2577638Y110632D01*
X2577258Y111132D01*
X2576815Y111299D01*
X2574851D01*
G01X2581408Y108632D02*
X2581028Y108715D01*
X2580648Y109049D01*
X2580395Y109632D01*
X2580268Y110299D01*
X2580395Y110965D01*
X2580648Y111549D01*
X2581028Y111882D01*
X2581408Y111965D01*
X2581788Y111882D01*
X2582168Y111549D01*
X2582421Y110965D01*
X2582485Y110299D01*
X2582421Y109632D01*
X2582168Y109049D01*
X2581788Y108715D01*
X2581408Y108632D01*
G01X2587648D02*
Y111965D01*
G01Y111382D02*
X2587395Y111715D01*
X2587015Y111882D01*
X2586571Y111965D01*
X2586128Y111799D01*
X2585748Y111465D01*
X2585495Y110965D01*
X2585368Y110299D01*
X2585495Y109632D01*
X2585748Y109132D01*
X2586128Y108799D01*
X2586571Y108632D01*
X2587015Y108715D01*
X2587395Y108965D01*
X2587648Y109299D01*
G01X2590721Y108632D02*
Y111965D01*
G01Y111299D02*
X2591038Y111632D01*
X2591355Y111882D01*
X2591798Y111965D01*
X2592115Y111882D01*
X2592495Y111632D01*
G01X2597848Y113632D02*
Y108632D01*
G01Y109382D02*
X2597595Y108965D01*
X2597215Y108715D01*
X2596771Y108632D01*
X2596265Y108799D01*
X2595885Y109215D01*
X2595631Y109715D01*
X2595568Y110299D01*
X2595631Y110882D01*
X2595885Y111382D01*
X2596265Y111799D01*
X2596771Y111965D01*
X2597215Y111882D01*
X2597531Y111715D01*
X2597848Y111382D01*
G01X2523915Y133832D02*
Y138832D01*
X2525181D01*
X2525688Y138582D01*
X2526068Y138249D01*
X2526385Y137749D01*
X2526638Y137165D01*
X2526701Y136332D01*
X2526638Y135499D01*
X2526385Y134915D01*
X2526068Y134415D01*
X2525688Y134082D01*
X2525181Y133832D01*
X2523915D01*
G01X2530408Y137165D02*
Y133832D01*
G01Y138499D02*
X2530281Y138582D01*
Y138749D01*
X2530408Y138832D01*
X2530535Y138749D01*
Y138582D01*
X2530408Y138499D01*
G01X2536648Y133832D02*
Y137165D01*
G01Y136582D02*
X2536395Y136915D01*
X2536015Y137082D01*
X2535571Y137165D01*
X2535128Y136999D01*
X2534748Y136665D01*
X2534495Y136165D01*
X2534368Y135499D01*
X2534495Y134832D01*
X2534748Y134332D01*
X2535128Y133999D01*
X2535571Y133832D01*
X2536015Y133915D01*
X2536395Y134165D01*
X2536648Y134499D01*
G01X2538708Y133832D02*
Y137165D01*
G01Y136249D02*
X2538898Y136665D01*
X2539215Y136999D01*
X2539658Y137165D01*
X2540101Y136999D01*
X2540418Y136665D01*
X2540608Y136249D01*
Y133832D01*
G01Y136249D02*
X2540798Y136665D01*
X2541115Y136999D01*
X2541558Y137165D01*
X2542001Y136999D01*
X2542318Y136665D01*
X2542508Y136165D01*
Y133832D01*
G01X2544758Y136082D02*
X2546785D01*
X2546595Y136665D01*
X2546278Y136999D01*
X2545835Y137165D01*
X2545391Y137082D01*
X2545011Y136832D01*
X2544758Y136249D01*
X2544631Y135749D01*
Y135249D01*
X2544758Y134749D01*
X2545075Y134249D01*
X2545455Y133915D01*
X2545898Y133832D01*
X2546341Y133999D01*
X2546785Y134499D01*
G01X2550808Y138832D02*
Y133832D01*
G01X2549921Y137165D02*
X2551695D01*
G01X2554958Y136082D02*
X2556985D01*
X2556795Y136665D01*
X2556478Y136999D01*
X2556035Y137165D01*
X2555591Y137082D01*
X2555211Y136832D01*
X2554958Y136249D01*
X2554831Y135749D01*
Y135249D01*
X2554958Y134749D01*
X2555275Y134249D01*
X2555655Y133915D01*
X2556098Y133832D01*
X2556541Y133999D01*
X2556985Y134499D01*
G01X2560121Y133832D02*
Y137165D01*
G01Y136499D02*
X2560438Y136832D01*
X2560755Y137082D01*
X2561198Y137165D01*
X2561515Y137082D01*
X2561895Y136832D01*
G01X2569815Y134832D02*
X2570195Y134249D01*
X2570701Y133915D01*
X2571271Y133832D01*
X2571778Y133915D01*
X2572285Y134332D01*
X2572601Y134832D01*
X2572665Y135332D01*
X2572538Y135915D01*
X2572095Y136332D01*
X2571651Y136499D01*
X2571081D01*
G01X2571651D02*
X2572031Y136749D01*
X2572348Y137165D01*
X2572475Y137665D01*
X2572348Y138165D01*
X2572031Y138582D01*
X2571461Y138832D01*
X2570891Y138749D01*
X2570321Y138415D01*
G01X2574408Y133832D02*
Y137165D01*
G01Y136249D02*
X2574598Y136665D01*
X2574915Y136999D01*
X2575358Y137165D01*
X2575801Y136999D01*
X2576118Y136665D01*
X2576308Y136249D01*
Y133832D01*
G01Y136249D02*
X2576498Y136665D01*
X2576815Y136999D01*
X2577258Y137165D01*
X2577701Y136999D01*
X2578018Y136665D01*
X2578208Y136165D01*
Y133832D01*
G01X2579508D02*
Y137165D01*
G01Y136249D02*
X2579698Y136665D01*
X2580015Y136999D01*
X2580458Y137165D01*
X2580901Y136999D01*
X2581218Y136665D01*
X2581408Y136249D01*
Y133832D01*
G01Y136249D02*
X2581598Y136665D01*
X2581915Y136999D01*
X2582358Y137165D01*
X2582801Y136999D01*
X2583118Y136665D01*
X2583308Y136165D01*
Y133832D01*
G01X2590278Y134499D02*
X2590785Y134082D01*
X2591355Y133832D01*
X2591861D01*
X2592368Y134082D01*
X2592748Y134499D01*
X2592938Y135082D01*
X2592811Y135665D01*
X2592495Y136165D01*
X2591925Y136499D01*
X2591165Y136665D01*
X2590721Y136999D01*
X2590531Y137582D01*
X2590658Y138165D01*
X2590975Y138582D01*
X2591418Y138832D01*
X2591861D01*
X2592305Y138665D01*
X2592685Y138249D01*
G01X2596708Y133832D02*
X2596328Y133915D01*
X2595948Y134249D01*
X2595695Y134832D01*
X2595568Y135499D01*
X2595695Y136165D01*
X2595948Y136749D01*
X2596328Y137082D01*
X2596708Y137165D01*
X2597088Y137082D01*
X2597468Y136749D01*
X2597721Y136165D01*
X2597785Y135499D01*
X2597721Y134832D01*
X2597468Y134249D01*
X2597088Y133915D01*
X2596708Y133832D01*
G01X2601808D02*
Y138832D01*
G01X2608048D02*
Y133832D01*
G01Y134582D02*
X2607795Y134165D01*
X2607415Y133915D01*
X2606971Y133832D01*
X2606465Y133999D01*
X2606085Y134415D01*
X2605831Y134915D01*
X2605768Y135499D01*
X2605831Y136082D01*
X2606085Y136582D01*
X2606465Y136999D01*
X2606971Y137165D01*
X2607415Y137082D01*
X2607731Y136915D01*
X2608048Y136582D01*
G01X2611058Y136082D02*
X2613085D01*
X2612895Y136665D01*
X2612578Y136999D01*
X2612135Y137165D01*
X2611691Y137082D01*
X2611311Y136832D01*
X2611058Y136249D01*
X2610931Y135749D01*
Y135249D01*
X2611058Y134749D01*
X2611375Y134249D01*
X2611755Y133915D01*
X2612198Y133832D01*
X2612641Y133999D01*
X2613085Y134499D01*
G01X2616221Y133832D02*
Y137165D01*
G01Y136499D02*
X2616538Y136832D01*
X2616855Y137082D01*
X2617298Y137165D01*
X2617615Y137082D01*
X2617995Y136832D01*
G01X2620308Y133832D02*
Y137165D01*
G01Y136249D02*
X2620498Y136665D01*
X2620815Y136999D01*
X2621258Y137165D01*
X2621701Y136999D01*
X2622018Y136665D01*
X2622208Y136249D01*
Y133832D01*
G01Y136249D02*
X2622398Y136665D01*
X2622715Y136999D01*
X2623158Y137165D01*
X2623601Y136999D01*
X2623918Y136665D01*
X2624108Y136165D01*
Y133832D01*
G01X2628448D02*
Y137165D01*
G01Y136582D02*
X2628195Y136915D01*
X2627815Y137082D01*
X2627371Y137165D01*
X2626928Y136999D01*
X2626548Y136665D01*
X2626295Y136165D01*
X2626168Y135499D01*
X2626295Y134832D01*
X2626548Y134332D01*
X2626928Y133999D01*
X2627371Y133832D01*
X2627815Y133915D01*
X2628195Y134165D01*
X2628448Y134499D01*
G01X2631458Y134415D02*
X2631775Y134082D01*
X2632218Y133832D01*
X2632598D01*
X2632978Y133999D01*
X2633231Y134249D01*
X2633358Y134582D01*
X2633295Y135082D01*
X2633041Y135332D01*
X2631901Y135832D01*
X2631648Y136415D01*
X2631775Y136832D01*
X2632028Y137082D01*
X2632408Y137165D01*
X2632788Y137082D01*
X2633168Y136832D01*
G01X2636431Y133832D02*
Y138832D01*
G01X2638458Y137165D02*
X2636431Y135249D01*
G01X2637255Y135999D02*
X2638585Y133832D01*
G01X2447605Y146432D02*
Y151432D01*
X2450011D01*
G01X2449125Y149015D02*
X2447605D01*
G01X2453908Y149765D02*
Y146432D01*
G01Y151099D02*
X2453781Y151182D01*
Y151349D01*
X2453908Y151432D01*
X2454035Y151349D01*
Y151182D01*
X2453908Y151099D01*
G01X2460148Y151432D02*
Y146432D01*
G01Y147182D02*
X2459895Y146765D01*
X2459515Y146515D01*
X2459071Y146432D01*
X2458565Y146599D01*
X2458185Y147015D01*
X2457931Y147515D01*
X2457868Y148099D01*
X2457931Y148682D01*
X2458185Y149182D01*
X2458565Y149599D01*
X2459071Y149765D01*
X2459515Y149682D01*
X2459831Y149515D01*
X2460148Y149182D01*
G01X2463031Y149765D02*
Y147432D01*
X2463285Y146849D01*
X2463665Y146515D01*
X2464108Y146432D01*
X2464551Y146515D01*
X2464931Y146849D01*
X2465185Y147432D01*
G01Y146432D02*
Y149765D01*
G01X2470221Y149349D02*
X2469778Y149682D01*
X2469398Y149765D01*
X2468891Y149599D01*
X2468511Y149265D01*
X2468258Y148682D01*
X2468195Y148099D01*
X2468258Y147515D01*
X2468511Y147015D01*
X2468891Y146599D01*
X2469398Y146432D01*
X2469841Y146599D01*
X2470221Y146932D01*
G01X2474308Y149765D02*
Y146432D01*
G01Y151099D02*
X2474181Y151182D01*
Y151349D01*
X2474308Y151432D01*
X2474435Y151349D01*
Y151182D01*
X2474308Y151099D01*
G01X2480548Y146432D02*
Y149765D01*
G01Y149182D02*
X2480295Y149515D01*
X2479915Y149682D01*
X2479471Y149765D01*
X2479028Y149599D01*
X2478648Y149265D01*
X2478395Y148765D01*
X2478268Y148099D01*
X2478395Y147432D01*
X2478648Y146932D01*
X2479028Y146599D01*
X2479471Y146432D01*
X2479915Y146515D01*
X2480295Y146765D01*
X2480548Y147099D01*
G01X2484508Y146432D02*
Y151432D01*
G01X2493061Y146432D02*
Y151432D01*
X2494708Y147265D01*
X2496355Y151432D01*
Y146432D01*
G01X2500948D02*
Y149765D01*
G01Y149182D02*
X2500695Y149515D01*
X2500315Y149682D01*
X2499871Y149765D01*
X2499428Y149599D01*
X2499048Y149265D01*
X2498795Y148765D01*
X2498668Y148099D01*
X2498795Y147432D01*
X2499048Y146932D01*
X2499428Y146599D01*
X2499871Y146432D01*
X2500315Y146515D01*
X2500695Y146765D01*
X2500948Y147099D01*
G01X2504021Y146432D02*
Y149765D01*
G01Y149099D02*
X2504338Y149432D01*
X2504655Y149682D01*
X2505098Y149765D01*
X2505415Y149682D01*
X2505795Y149432D01*
G01X2508931Y146432D02*
Y151432D01*
G01X2510958Y149765D02*
X2508931Y147849D01*
G01X2509755Y148599D02*
X2511085Y146432D01*
G01X2515108Y146265D02*
X2514981Y146349D01*
Y146515D01*
X2515108Y146599D01*
X2515235Y146515D01*
Y146349D01*
X2515108Y146265D01*
G01Y148515D02*
X2514981Y148599D01*
Y148765D01*
X2515108Y148849D01*
X2515235Y148765D01*
Y148599D01*
X2515108Y148515D01*
G01X2523915Y146432D02*
Y151432D01*
X2525181D01*
X2525688Y151182D01*
X2526068Y150849D01*
X2526385Y150349D01*
X2526638Y149765D01*
X2526701Y148932D01*
X2526638Y148099D01*
X2526385Y147515D01*
X2526068Y147015D01*
X2525688Y146682D01*
X2525181Y146432D01*
X2523915D01*
G01X2530408Y149765D02*
Y146432D01*
G01Y151099D02*
X2530281Y151182D01*
Y151349D01*
X2530408Y151432D01*
X2530535Y151349D01*
Y151182D01*
X2530408Y151099D01*
G01X2536648Y146432D02*
Y149765D01*
G01Y149182D02*
X2536395Y149515D01*
X2536015Y149682D01*
X2535571Y149765D01*
X2535128Y149599D01*
X2534748Y149265D01*
X2534495Y148765D01*
X2534368Y148099D01*
X2534495Y147432D01*
X2534748Y146932D01*
X2535128Y146599D01*
X2535571Y146432D01*
X2536015Y146515D01*
X2536395Y146765D01*
X2536648Y147099D01*
G01X2538708Y146432D02*
Y149765D01*
G01Y148849D02*
X2538898Y149265D01*
X2539215Y149599D01*
X2539658Y149765D01*
X2540101Y149599D01*
X2540418Y149265D01*
X2540608Y148849D01*
Y146432D01*
G01Y148849D02*
X2540798Y149265D01*
X2541115Y149599D01*
X2541558Y149765D01*
X2542001Y149599D01*
X2542318Y149265D01*
X2542508Y148765D01*
Y146432D01*
G01X2544758Y148682D02*
X2546785D01*
X2546595Y149265D01*
X2546278Y149599D01*
X2545835Y149765D01*
X2545391Y149682D01*
X2545011Y149432D01*
X2544758Y148849D01*
X2544631Y148349D01*
Y147849D01*
X2544758Y147349D01*
X2545075Y146849D01*
X2545455Y146515D01*
X2545898Y146432D01*
X2546341Y146599D01*
X2546785Y147099D01*
G01X2550808Y151432D02*
Y146432D01*
G01X2549921Y149765D02*
X2551695D01*
G01X2554958Y148682D02*
X2556985D01*
X2556795Y149265D01*
X2556478Y149599D01*
X2556035Y149765D01*
X2555591Y149682D01*
X2555211Y149432D01*
X2554958Y148849D01*
X2554831Y148349D01*
Y147849D01*
X2554958Y147349D01*
X2555275Y146849D01*
X2555655Y146515D01*
X2556098Y146432D01*
X2556541Y146599D01*
X2556985Y147099D01*
G01X2560121Y146432D02*
Y149765D01*
G01Y149099D02*
X2560438Y149432D01*
X2560755Y149682D01*
X2561198Y149765D01*
X2561515Y149682D01*
X2561895Y149432D01*
G01X2571208Y146432D02*
Y151432D01*
X2570448Y150432D01*
G01Y146432D02*
X2571968D01*
G01X2574408D02*
Y149765D01*
G01Y148849D02*
X2574598Y149265D01*
X2574915Y149599D01*
X2575358Y149765D01*
X2575801Y149599D01*
X2576118Y149265D01*
X2576308Y148849D01*
Y146432D01*
G01Y148849D02*
X2576498Y149265D01*
X2576815Y149599D01*
X2577258Y149765D01*
X2577701Y149599D01*
X2578018Y149265D01*
X2578208Y148765D01*
Y146432D01*
G01X2579508D02*
Y149765D01*
G01Y148849D02*
X2579698Y149265D01*
X2580015Y149599D01*
X2580458Y149765D01*
X2580901Y149599D01*
X2581218Y149265D01*
X2581408Y148849D01*
Y146432D01*
G01Y148849D02*
X2581598Y149265D01*
X2581915Y149599D01*
X2582358Y149765D01*
X2582801Y149599D01*
X2583118Y149265D01*
X2583308Y148765D01*
Y146432D01*
G01X2593001Y151015D02*
X2592621Y151265D01*
X2592178Y151432D01*
X2591671D01*
X2591101Y151182D01*
X2590658Y150765D01*
X2590341Y150265D01*
X2590088Y149432D01*
X2590025Y148682D01*
X2590151Y147932D01*
X2590341Y147432D01*
X2590721Y146932D01*
X2591165Y146599D01*
X2591608Y146432D01*
X2592051D01*
X2592495Y146599D01*
X2592875Y146849D01*
X2593191Y147182D01*
G01X2596708Y146432D02*
X2596328Y146515D01*
X2595948Y146849D01*
X2595695Y147432D01*
X2595568Y148099D01*
X2595695Y148765D01*
X2595948Y149349D01*
X2596328Y149682D01*
X2596708Y149765D01*
X2597088Y149682D01*
X2597468Y149349D01*
X2597721Y148765D01*
X2597785Y148099D01*
X2597721Y147432D01*
X2597468Y146849D01*
X2597088Y146515D01*
X2596708Y146432D01*
G01X2600668Y144765D02*
Y149765D01*
G01Y149015D02*
X2600985Y149432D01*
X2601301Y149682D01*
X2601808Y149765D01*
X2602251Y149682D01*
X2602695Y149265D01*
X2602885Y148682D01*
X2602948Y148099D01*
X2602885Y147515D01*
X2602695Y146932D01*
X2602315Y146599D01*
X2601808Y146432D01*
X2601365Y146515D01*
X2600921Y146765D01*
X2600668Y147099D01*
G01X2605768Y144765D02*
Y149765D01*
G01Y149015D02*
X2606085Y149432D01*
X2606401Y149682D01*
X2606908Y149765D01*
X2607351Y149682D01*
X2607795Y149265D01*
X2607985Y148682D01*
X2608048Y148099D01*
X2607985Y147515D01*
X2607795Y146932D01*
X2607415Y146599D01*
X2606908Y146432D01*
X2606465Y146515D01*
X2606021Y146765D01*
X2605768Y147099D01*
G01X2611058Y148682D02*
X2613085D01*
X2612895Y149265D01*
X2612578Y149599D01*
X2612135Y149765D01*
X2611691Y149682D01*
X2611311Y149432D01*
X2611058Y148849D01*
X2610931Y148349D01*
Y147849D01*
X2611058Y147349D01*
X2611375Y146849D01*
X2611755Y146515D01*
X2612198Y146432D01*
X2612641Y146599D01*
X2613085Y147099D01*
G01X2616221Y146432D02*
Y149765D01*
G01Y149099D02*
X2616538Y149432D01*
X2616855Y149682D01*
X2617298Y149765D01*
X2617615Y149682D01*
X2617995Y149432D01*
G01X2520996Y208124D02*
Y203124D01*
G01X2519539Y208124D02*
X2522453D01*
G01X2526096Y203124D02*
X2525716Y203207D01*
X2525336Y203541D01*
X2525083Y204124D01*
X2524956Y204791D01*
X2525083Y205457D01*
X2525336Y206041D01*
X2525716Y206374D01*
X2526096Y206457D01*
X2526476Y206374D01*
X2526856Y206041D01*
X2527109Y205457D01*
X2527173Y204791D01*
X2527109Y204124D01*
X2526856Y203541D01*
X2526476Y203207D01*
X2526096Y203124D01*
G01X2531196D02*
Y208124D01*
G01X2535346Y205374D02*
X2537373D01*
X2537183Y205957D01*
X2536866Y206291D01*
X2536423Y206457D01*
X2535979Y206374D01*
X2535599Y206124D01*
X2535346Y205541D01*
X2535219Y205041D01*
Y204541D01*
X2535346Y204041D01*
X2535663Y203541D01*
X2536043Y203207D01*
X2536486Y203124D01*
X2536929Y203291D01*
X2537373Y203791D01*
G01X2540509Y203124D02*
Y206457D01*
G01Y205791D02*
X2540826Y206124D01*
X2541143Y206374D01*
X2541586Y206457D01*
X2541903Y206374D01*
X2542283Y206124D01*
G01X2547636Y203124D02*
Y206457D01*
G01Y205874D02*
X2547383Y206207D01*
X2547003Y206374D01*
X2546559Y206457D01*
X2546116Y206291D01*
X2545736Y205957D01*
X2545483Y205457D01*
X2545356Y204791D01*
X2545483Y204124D01*
X2545736Y203624D01*
X2546116Y203291D01*
X2546559Y203124D01*
X2547003Y203207D01*
X2547383Y203457D01*
X2547636Y203791D01*
G01X2550519Y203124D02*
Y206457D01*
G01Y205624D02*
X2550773Y206041D01*
X2551153Y206374D01*
X2551659Y206457D01*
X2552103Y206374D01*
X2552483Y206041D01*
X2552673Y205457D01*
Y203124D01*
G01X2557709Y206041D02*
X2557266Y206374D01*
X2556886Y206457D01*
X2556379Y206291D01*
X2555999Y205957D01*
X2555746Y205374D01*
X2555683Y204791D01*
X2555746Y204207D01*
X2555999Y203707D01*
X2556379Y203291D01*
X2556886Y203124D01*
X2557329Y203291D01*
X2557709Y203624D01*
G01X2560846Y205374D02*
X2562873D01*
X2562683Y205957D01*
X2562366Y206291D01*
X2561923Y206457D01*
X2561479Y206374D01*
X2561099Y206124D01*
X2560846Y205541D01*
X2560719Y205041D01*
Y204541D01*
X2560846Y204041D01*
X2561163Y203541D01*
X2561543Y203207D01*
X2561986Y203124D01*
X2562429Y203291D01*
X2562873Y203791D01*
G01X2571299Y204791D02*
X2572819D01*
G01X2571996Y205874D02*
Y203707D01*
G01X2577096Y208124D02*
X2576589Y207957D01*
X2576209Y207541D01*
X2575956Y207041D01*
X2575766Y206374D01*
X2575703Y205624D01*
X2575766Y204874D01*
X2575956Y204207D01*
X2576209Y203707D01*
X2576589Y203291D01*
X2577096Y203124D01*
X2577603Y203291D01*
X2577983Y203707D01*
X2578236Y204207D01*
X2578426Y204874D01*
X2578489Y205624D01*
X2578426Y206374D01*
X2578236Y207041D01*
X2577983Y207541D01*
X2577603Y207957D01*
X2577096Y208124D01*
G01X2582196Y202957D02*
X2582069Y203041D01*
Y203207D01*
X2582196Y203291D01*
X2582323Y203207D01*
Y203041D01*
X2582196Y202957D01*
G01X2587296Y208124D02*
X2586789Y207957D01*
X2586409Y207541D01*
X2586156Y207041D01*
X2585966Y206374D01*
X2585903Y205624D01*
X2585966Y204874D01*
X2586156Y204207D01*
X2586409Y203707D01*
X2586789Y203291D01*
X2587296Y203124D01*
X2587803Y203291D01*
X2588183Y203707D01*
X2588436Y204207D01*
X2588626Y204874D01*
X2588689Y205624D01*
X2588626Y206374D01*
X2588436Y207041D01*
X2588183Y207541D01*
X2587803Y207957D01*
X2587296Y208124D01*
G01X2591003Y203874D02*
X2591383Y203457D01*
X2591826Y203207D01*
X2592396Y203124D01*
X2592966Y203291D01*
X2593409Y203624D01*
X2593726Y204207D01*
X2593789Y204874D01*
X2593663Y205541D01*
X2593346Y205957D01*
X2592903Y206291D01*
X2592459Y206374D01*
X2592016Y206291D01*
X2591446Y205957D01*
X2591636Y208124D01*
X2593346D01*
G01X2597496D02*
X2596989Y207957D01*
X2596609Y207541D01*
X2596356Y207041D01*
X2596166Y206374D01*
X2596103Y205624D01*
X2596166Y204874D01*
X2596356Y204207D01*
X2596609Y203707D01*
X2596989Y203291D01*
X2597496Y203124D01*
X2598003Y203291D01*
X2598383Y203707D01*
X2598636Y204207D01*
X2598826Y204874D01*
X2598889Y205624D01*
X2598826Y206374D01*
X2598636Y207041D01*
X2598383Y207541D01*
X2598003Y207957D01*
X2597496Y208124D01*
G01X2602596Y203124D02*
X2603039Y203207D01*
X2603546Y203457D01*
X2603863Y203874D01*
X2603989Y204457D01*
X2603863Y205041D01*
X2603483Y205541D01*
X2602913Y205791D01*
X2602279D01*
X2601899Y205957D01*
X2601583Y206374D01*
X2601456Y206957D01*
X2601646Y207541D01*
X2602089Y207957D01*
X2602596Y208124D01*
X2603103Y207957D01*
X2603546Y207541D01*
X2603736Y206957D01*
X2603609Y206374D01*
X2603293Y205957D01*
X2602913Y205791D01*
X2602279D01*
X2601709Y205541D01*
X2601329Y205041D01*
X2601203Y204457D01*
X2601329Y203874D01*
X2601646Y203457D01*
X2602153Y203207D01*
X2602596Y203124D01*
G01X2605796D02*
Y206457D01*
G01Y205541D02*
X2605986Y205957D01*
X2606303Y206291D01*
X2606746Y206457D01*
X2607189Y206291D01*
X2607506Y205957D01*
X2607696Y205541D01*
Y203124D01*
G01Y205541D02*
X2607886Y205957D01*
X2608203Y206291D01*
X2608646Y206457D01*
X2609089Y206291D01*
X2609406Y205957D01*
X2609596Y205457D01*
Y203124D01*
G01X2610896D02*
Y206457D01*
G01Y205541D02*
X2611086Y205957D01*
X2611403Y206291D01*
X2611846Y206457D01*
X2612289Y206291D01*
X2612606Y205957D01*
X2612796Y205541D01*
Y203124D01*
G01Y205541D02*
X2612986Y205957D01*
X2613303Y206291D01*
X2613746Y206457D01*
X2614189Y206291D01*
X2614506Y205957D01*
X2614696Y205457D01*
Y203124D01*
G01X2616756Y202957D02*
X2619036Y208124D01*
G01X2622173Y204791D02*
X2623819D01*
G01X2628096Y208124D02*
X2627589Y207957D01*
X2627209Y207541D01*
X2626956Y207041D01*
X2626766Y206374D01*
X2626703Y205624D01*
X2626766Y204874D01*
X2626956Y204207D01*
X2627209Y203707D01*
X2627589Y203291D01*
X2628096Y203124D01*
X2628603Y203291D01*
X2628983Y203707D01*
X2629236Y204207D01*
X2629426Y204874D01*
X2629489Y205624D01*
X2629426Y206374D01*
X2629236Y207041D01*
X2628983Y207541D01*
X2628603Y207957D01*
X2628096Y208124D01*
G01X2633196Y202957D02*
X2633069Y203041D01*
Y203207D01*
X2633196Y203291D01*
X2633323Y203207D01*
Y203041D01*
X2633196Y202957D01*
G01X2638296Y208124D02*
X2637789Y207957D01*
X2637409Y207541D01*
X2637156Y207041D01*
X2636966Y206374D01*
X2636903Y205624D01*
X2636966Y204874D01*
X2637156Y204207D01*
X2637409Y203707D01*
X2637789Y203291D01*
X2638296Y203124D01*
X2638803Y203291D01*
X2639183Y203707D01*
X2639436Y204207D01*
X2639626Y204874D01*
X2639689Y205624D01*
X2639626Y206374D01*
X2639436Y207041D01*
X2639183Y207541D01*
X2638803Y207957D01*
X2638296Y208124D01*
G01X2643396D02*
X2642889Y207957D01*
X2642509Y207541D01*
X2642256Y207041D01*
X2642066Y206374D01*
X2642003Y205624D01*
X2642066Y204874D01*
X2642256Y204207D01*
X2642509Y203707D01*
X2642889Y203291D01*
X2643396Y203124D01*
X2643903Y203291D01*
X2644283Y203707D01*
X2644536Y204207D01*
X2644726Y204874D01*
X2644789Y205624D01*
X2644726Y206374D01*
X2644536Y207041D01*
X2644283Y207541D01*
X2643903Y207957D01*
X2643396Y208124D01*
G01X2648496D02*
X2647989Y207957D01*
X2647609Y207541D01*
X2647356Y207041D01*
X2647166Y206374D01*
X2647103Y205624D01*
X2647166Y204874D01*
X2647356Y204207D01*
X2647609Y203707D01*
X2647989Y203291D01*
X2648496Y203124D01*
X2649003Y203291D01*
X2649383Y203707D01*
X2649636Y204207D01*
X2649826Y204874D01*
X2649889Y205624D01*
X2649826Y206374D01*
X2649636Y207041D01*
X2649383Y207541D01*
X2649003Y207957D01*
X2648496Y208124D01*
G01X2653596D02*
X2653089Y207957D01*
X2652709Y207541D01*
X2652456Y207041D01*
X2652266Y206374D01*
X2652203Y205624D01*
X2652266Y204874D01*
X2652456Y204207D01*
X2652709Y203707D01*
X2653089Y203291D01*
X2653596Y203124D01*
X2654103Y203291D01*
X2654483Y203707D01*
X2654736Y204207D01*
X2654926Y204874D01*
X2654989Y205624D01*
X2654926Y206374D01*
X2654736Y207041D01*
X2654483Y207541D01*
X2654103Y207957D01*
X2653596Y208124D01*
G01X2656796Y203124D02*
Y206457D01*
G01Y205541D02*
X2656986Y205957D01*
X2657303Y206291D01*
X2657746Y206457D01*
X2658189Y206291D01*
X2658506Y205957D01*
X2658696Y205541D01*
Y203124D01*
G01Y205541D02*
X2658886Y205957D01*
X2659203Y206291D01*
X2659646Y206457D01*
X2660089Y206291D01*
X2660406Y205957D01*
X2660596Y205457D01*
Y203124D01*
G01X2661896D02*
Y206457D01*
G01Y205541D02*
X2662086Y205957D01*
X2662403Y206291D01*
X2662846Y206457D01*
X2663289Y206291D01*
X2663606Y205957D01*
X2663796Y205541D01*
Y203124D01*
G01Y205541D02*
X2663986Y205957D01*
X2664303Y206291D01*
X2664746Y206457D01*
X2665189Y206291D01*
X2665506Y205957D01*
X2665696Y205457D01*
Y203124D01*
G01X2449596Y220724D02*
Y215724D01*
G01X2448139Y220724D02*
X2451053D01*
G01X2454696Y215724D02*
X2454316Y215807D01*
X2453936Y216141D01*
X2453683Y216724D01*
X2453556Y217391D01*
X2453683Y218057D01*
X2453936Y218641D01*
X2454316Y218974D01*
X2454696Y219057D01*
X2455076Y218974D01*
X2455456Y218641D01*
X2455709Y218057D01*
X2455773Y217391D01*
X2455709Y216724D01*
X2455456Y216141D01*
X2455076Y215807D01*
X2454696Y215724D01*
G01X2459796D02*
X2459416Y215807D01*
X2459036Y216141D01*
X2458783Y216724D01*
X2458656Y217391D01*
X2458783Y218057D01*
X2459036Y218641D01*
X2459416Y218974D01*
X2459796Y219057D01*
X2460176Y218974D01*
X2460556Y218641D01*
X2460809Y218057D01*
X2460873Y217391D01*
X2460809Y216724D01*
X2460556Y216141D01*
X2460176Y215807D01*
X2459796Y215724D01*
G01X2464896D02*
Y220724D01*
G01X2469996Y219057D02*
Y215724D01*
G01Y220391D02*
X2469869Y220474D01*
Y220641D01*
X2469996Y220724D01*
X2470123Y220641D01*
Y220474D01*
X2469996Y220391D01*
G01X2474019Y215724D02*
Y219057D01*
G01Y218224D02*
X2474273Y218641D01*
X2474653Y218974D01*
X2475159Y219057D01*
X2475603Y218974D01*
X2475983Y218641D01*
X2476173Y218057D01*
Y215724D01*
G01X2479309Y214474D02*
X2479753Y214141D01*
X2480259Y214057D01*
X2480703Y214141D01*
X2481083Y214557D01*
X2481336Y215141D01*
Y219057D01*
G01Y218391D02*
X2481083Y218724D01*
X2480703Y218974D01*
X2480259Y219057D01*
X2479753Y218891D01*
X2479436Y218557D01*
X2479183Y217974D01*
X2479056Y217391D01*
X2479119Y216891D01*
X2479373Y216307D01*
X2479753Y215891D01*
X2480259Y215724D01*
X2480639Y215807D01*
X2481083Y216141D01*
X2481336Y216474D01*
G01X2489066Y215724D02*
Y220724D01*
G01X2491726D02*
Y215724D01*
G01Y218224D02*
X2489066D01*
G01X2495496Y215724D02*
X2495116Y215807D01*
X2494736Y216141D01*
X2494483Y216724D01*
X2494356Y217391D01*
X2494483Y218057D01*
X2494736Y218641D01*
X2495116Y218974D01*
X2495496Y219057D01*
X2495876Y218974D01*
X2496256Y218641D01*
X2496509Y218057D01*
X2496573Y217391D01*
X2496509Y216724D01*
X2496256Y216141D01*
X2495876Y215807D01*
X2495496Y215724D01*
G01X2500596D02*
Y220724D01*
G01X2504746Y217974D02*
X2506773D01*
X2506583Y218557D01*
X2506266Y218891D01*
X2505823Y219057D01*
X2505379Y218974D01*
X2504999Y218724D01*
X2504746Y218141D01*
X2504619Y217641D01*
Y217141D01*
X2504746Y216641D01*
X2505063Y216141D01*
X2505443Y215807D01*
X2505886Y215724D01*
X2506329Y215891D01*
X2506773Y216391D01*
G01X2510796Y215557D02*
X2510669Y215641D01*
Y215807D01*
X2510796Y215891D01*
X2510923Y215807D01*
Y215641D01*
X2510796Y215557D01*
G01Y217807D02*
X2510669Y217891D01*
Y218057D01*
X2510796Y218141D01*
X2510923Y218057D01*
Y217891D01*
X2510796Y217807D01*
G01X2519603Y215724D02*
Y220724D01*
X2520869D01*
X2521376Y220474D01*
X2521756Y220141D01*
X2522073Y219641D01*
X2522326Y219057D01*
X2522389Y218224D01*
X2522326Y217391D01*
X2522073Y216807D01*
X2521756Y216307D01*
X2521376Y215974D01*
X2520869Y215724D01*
X2519603D01*
G01X2526096Y219057D02*
Y215724D01*
G01Y220391D02*
X2525969Y220474D01*
Y220641D01*
X2526096Y220724D01*
X2526223Y220641D01*
Y220474D01*
X2526096Y220391D01*
G01X2532336Y215724D02*
Y219057D01*
G01Y218474D02*
X2532083Y218807D01*
X2531703Y218974D01*
X2531259Y219057D01*
X2530816Y218891D01*
X2530436Y218557D01*
X2530183Y218057D01*
X2530056Y217391D01*
X2530183Y216724D01*
X2530436Y216224D01*
X2530816Y215891D01*
X2531259Y215724D01*
X2531703Y215807D01*
X2532083Y216057D01*
X2532336Y216391D01*
G01X2534396Y215724D02*
Y219057D01*
G01Y218141D02*
X2534586Y218557D01*
X2534903Y218891D01*
X2535346Y219057D01*
X2535789Y218891D01*
X2536106Y218557D01*
X2536296Y218141D01*
Y215724D01*
G01Y218141D02*
X2536486Y218557D01*
X2536803Y218891D01*
X2537246Y219057D01*
X2537689Y218891D01*
X2538006Y218557D01*
X2538196Y218057D01*
Y215724D01*
G01X2540446Y217974D02*
X2542473D01*
X2542283Y218557D01*
X2541966Y218891D01*
X2541523Y219057D01*
X2541079Y218974D01*
X2540699Y218724D01*
X2540446Y218141D01*
X2540319Y217641D01*
Y217141D01*
X2540446Y216641D01*
X2540763Y216141D01*
X2541143Y215807D01*
X2541586Y215724D01*
X2542029Y215891D01*
X2542473Y216391D01*
G01X2546496Y220724D02*
Y215724D01*
G01X2545609Y219057D02*
X2547383D01*
G01X2550646Y217974D02*
X2552673D01*
X2552483Y218557D01*
X2552166Y218891D01*
X2551723Y219057D01*
X2551279Y218974D01*
X2550899Y218724D01*
X2550646Y218141D01*
X2550519Y217641D01*
Y217141D01*
X2550646Y216641D01*
X2550963Y216141D01*
X2551343Y215807D01*
X2551786Y215724D01*
X2552229Y215891D01*
X2552673Y216391D01*
G01X2555809Y215724D02*
Y219057D01*
G01Y218391D02*
X2556126Y218724D01*
X2556443Y218974D01*
X2556886Y219057D01*
X2557203Y218974D01*
X2557583Y218724D01*
G01X2565503Y216724D02*
X2565883Y216141D01*
X2566389Y215807D01*
X2566959Y215724D01*
X2567466Y215807D01*
X2567973Y216224D01*
X2568289Y216724D01*
X2568353Y217224D01*
X2568226Y217807D01*
X2567783Y218224D01*
X2567339Y218391D01*
X2566769D01*
G01X2567339D02*
X2567719Y218641D01*
X2568036Y219057D01*
X2568163Y219557D01*
X2568036Y220057D01*
X2567719Y220474D01*
X2567149Y220724D01*
X2566579Y220641D01*
X2566009Y220307D01*
G01X2571996Y215557D02*
X2571869Y215641D01*
Y215807D01*
X2571996Y215891D01*
X2572123Y215807D01*
Y215641D01*
X2571996Y215557D01*
G01X2577096Y215724D02*
Y220724D01*
X2576336Y219724D01*
G01Y215724D02*
X2577856D01*
G01X2582069D02*
X2582196Y216807D01*
X2582386Y217724D01*
X2582639Y218557D01*
X2582956Y219474D01*
X2583463Y220724D01*
X2580929D01*
G01X2585903Y216474D02*
X2586283Y216057D01*
X2586726Y215807D01*
X2587296Y215724D01*
X2587866Y215891D01*
X2588309Y216224D01*
X2588626Y216807D01*
X2588689Y217474D01*
X2588563Y218141D01*
X2588246Y218557D01*
X2587803Y218891D01*
X2587359Y218974D01*
X2586916Y218891D01*
X2586346Y218557D01*
X2586536Y220724D01*
X2588246D01*
G01X2590496Y215724D02*
Y219057D01*
G01Y218141D02*
X2590686Y218557D01*
X2591003Y218891D01*
X2591446Y219057D01*
X2591889Y218891D01*
X2592206Y218557D01*
X2592396Y218141D01*
Y215724D01*
G01Y218141D02*
X2592586Y218557D01*
X2592903Y218891D01*
X2593346Y219057D01*
X2593789Y218891D01*
X2594106Y218557D01*
X2594296Y218057D01*
Y215724D01*
G01X2595596D02*
Y219057D01*
G01Y218141D02*
X2595786Y218557D01*
X2596103Y218891D01*
X2596546Y219057D01*
X2596989Y218891D01*
X2597306Y218557D01*
X2597496Y218141D01*
Y215724D01*
G01Y218141D02*
X2597686Y218557D01*
X2598003Y218891D01*
X2598446Y219057D01*
X2598889Y218891D01*
X2599206Y218557D01*
X2599396Y218057D01*
Y215724D01*
G01X2606239D02*
Y220724D01*
X2609153Y215724D01*
Y220724D01*
G01X2611529Y215724D02*
Y220724D01*
X2613049D01*
X2613556Y220474D01*
X2613936Y219891D01*
X2614063Y219224D01*
X2613936Y218557D01*
X2613619Y218057D01*
X2613049Y217807D01*
X2611529D01*
G01X2617896Y220724D02*
Y215724D01*
G01X2616439Y220724D02*
X2619353D01*
G01X2621666Y215724D02*
Y220724D01*
G01X2624326D02*
Y215724D01*
G01Y218224D02*
X2621666D01*
G01X2468352Y5072D02*
X2467852Y5452D01*
X2467602Y5895D01*
X2467519Y6402D01*
X2467686Y7035D01*
X2468102Y7478D01*
X2468602Y7605D01*
X2469102Y7542D01*
X2469519Y7288D01*
X2470352Y6022D01*
X2470936Y5452D01*
X2471769Y5072D01*
X2472519Y4945D01*
Y7605D01*
G01X2476003Y-3568D02*
X2475019Y2338D01*
X2474034Y-3568D01*
X2476003D01*
G01X2475019Y6275D02*
Y2338D01*
G01X2489586D02*
X2474625D01*
G01X2474034Y16117D02*
X2475019Y10212D01*
X2476003Y16117D01*
X2474034D01*
G01X2475019Y6275D02*
Y10212D01*
G01X2489586D02*
X2474625D01*
G01X2476849Y82952D02*
X2490312Y61411D01*
G01X2482398Y85507D02*
X2512727Y92506D01*
G01X2487931Y87794D02*
X2482398Y85507D01*
X2488374Y85876D01*
X2487931Y87794D01*
G01X2480814Y78466D02*
X2476849Y82952D01*
X2479145Y77423D01*
X2480814Y78466D01*
G01X2493042Y73553D02*
X2484032Y73818D01*
G01X2482144Y183294D02*
X2526247Y193059D01*
G01X2487698Y185532D02*
X2482144Y183294D01*
X2488123Y183610D01*
X2487698Y185532D01*
G01X2498247Y-16363D02*
X2504152Y-15379D01*
X2498247Y-14394D01*
Y-16363D01*
G01X2489438Y67527D02*
X2493678Y70177D01*
X2492427Y70291D01*
G01X2489035Y68171D02*
X2489841Y66882D01*
G01X2491037Y73686D02*
G03I-2500J0D01*
G01X2502136Y99041D02*
X2498951Y90610D01*
G01X2503044Y94825D02*
G03I-2501J0D01*
G01X2498696Y190544D02*
X2499193Y190056D01*
X2499759Y189841D01*
X2500334Y189882D01*
X2500811Y190073D01*
X2501215Y190590D01*
X2501416Y191146D01*
X2501370Y191648D01*
X2501120Y192190D01*
X2500597Y192501D01*
X2500128Y192568D01*
X2499572Y192445D01*
G01X2500128Y192568D02*
X2500445Y192894D01*
X2500665Y193370D01*
X2500680Y193885D01*
X2500448Y194346D01*
X2500049Y194684D01*
X2499439Y194805D01*
X2498900Y194601D01*
X2498416Y194152D01*
G01X2505287Y190808D02*
X2505145Y190862D01*
X2505109Y191025D01*
X2505215Y191133D01*
X2505357Y191079D01*
X2505393Y190917D01*
X2505287Y190808D01*
G01X2510230Y192073D02*
X2509149Y196954D01*
X2508623Y195814D01*
G01X2509488Y191908D02*
X2510972Y192237D01*
G01X2515085Y193147D02*
X2514975Y194232D01*
X2514962Y195168D01*
X2515029Y196037D01*
X2515141Y197000D01*
X2515365Y198330D01*
X2512892Y197783D01*
G01X2518666Y194708D02*
X2519127Y194383D01*
X2519613Y194235D01*
X2520188Y194277D01*
X2520709Y194563D01*
X2521069Y194984D01*
X2521252Y195622D01*
X2521170Y196286D01*
X2520902Y196910D01*
X2520503Y197248D01*
X2519998Y197478D01*
X2519547Y197463D01*
X2519133Y197286D01*
X2518648Y196838D01*
X2518365Y198994D01*
X2520035Y199364D01*
G01X2495797Y195279D02*
X2492536Y186876D01*
G01X2496666Y191077D02*
G03I-2500J0D01*
G01X2509059Y-11879D02*
X2509439Y-12462D01*
X2509945Y-12796D01*
X2510515Y-12879D01*
X2511022Y-12796D01*
X2511529Y-12379D01*
X2511845Y-11879D01*
X2511909Y-11379D01*
X2511782Y-10796D01*
X2511339Y-10379D01*
X2510895Y-10212D01*
X2510325D01*
G01X2510895D02*
X2511275Y-9962D01*
X2511592Y-9546D01*
X2511719Y-9046D01*
X2511592Y-8546D01*
X2511275Y-8129D01*
X2510705Y-7879D01*
X2510135Y-7962D01*
X2509565Y-8296D01*
G01X2521869Y-14394D02*
X2515963Y-15379D01*
X2521869Y-16363D01*
Y-14394D01*
G01X2510452Y-15379D02*
X2515963D01*
G01X2510452D02*
X2504152D01*
G01X2515963Y3913D02*
Y-15772D01*
G01X2504152Y3913D02*
Y-15772D01*
G01X2505077Y94332D02*
X2505578Y93849D01*
X2506147Y93638D01*
X2506721Y93685D01*
X2507196Y93881D01*
X2507596Y94400D01*
X2507792Y94959D01*
X2507741Y95460D01*
X2507487Y96000D01*
X2506961Y96306D01*
X2506492Y96369D01*
X2505936Y96241D01*
G01X2506492Y96369D02*
X2506806Y96698D01*
X2507021Y97175D01*
X2507032Y97691D01*
X2506796Y98150D01*
X2506394Y98485D01*
X2505782Y98600D01*
X2505245Y98391D01*
X2504765Y97938D01*
G01X2624470Y-59867D02*
Y-54867D01*
X2625990D01*
X2626497Y-55117D01*
X2626877Y-55700D01*
X2627004Y-56367D01*
X2626877Y-57034D01*
X2626560Y-57534D01*
X2625990Y-57784D01*
X2624470D01*
G01X2631977Y-59867D02*
Y-56534D01*
G01Y-57117D02*
X2631724Y-56784D01*
X2631344Y-56617D01*
X2630900Y-56534D01*
X2630457Y-56700D01*
X2630077Y-57034D01*
X2629824Y-57534D01*
X2629697Y-58200D01*
X2629824Y-58867D01*
X2630077Y-59367D01*
X2630457Y-59700D01*
X2630900Y-59867D01*
X2631344Y-59784D01*
X2631724Y-59534D01*
X2631977Y-59200D01*
G01X2634860Y-59867D02*
Y-56534D01*
G01Y-57367D02*
X2635114Y-56950D01*
X2635494Y-56617D01*
X2636000Y-56534D01*
X2636444Y-56617D01*
X2636824Y-56950D01*
X2637014Y-57534D01*
Y-59867D01*
G01X2640087Y-57617D02*
X2642114D01*
X2641924Y-57034D01*
X2641607Y-56700D01*
X2641164Y-56534D01*
X2640720Y-56617D01*
X2640340Y-56867D01*
X2640087Y-57450D01*
X2639960Y-57950D01*
Y-58450D01*
X2640087Y-58950D01*
X2640404Y-59450D01*
X2640784Y-59784D01*
X2641227Y-59867D01*
X2641670Y-59700D01*
X2642114Y-59200D01*
G01X2646137Y-59867D02*
Y-54867D01*
G01X2655070Y-59867D02*
Y-54867D01*
X2656654D01*
X2657160Y-55117D01*
X2657477Y-55450D01*
X2657604Y-56117D01*
X2657477Y-56784D01*
X2657097Y-57200D01*
X2656654Y-57450D01*
X2655070D01*
G01X2656654D02*
X2657604Y-59867D01*
G01X2660487Y-57617D02*
X2662514D01*
X2662324Y-57034D01*
X2662007Y-56700D01*
X2661564Y-56534D01*
X2661120Y-56617D01*
X2660740Y-56867D01*
X2660487Y-57450D01*
X2660360Y-57950D01*
Y-58450D01*
X2660487Y-58950D01*
X2660804Y-59450D01*
X2661184Y-59784D01*
X2661627Y-59867D01*
X2662070Y-59700D01*
X2662514Y-59200D01*
G01X2665397Y-56534D02*
X2666537Y-59867D01*
X2667677Y-56534D01*
G01X2677244Y-57200D02*
X2677497Y-56950D01*
X2677687Y-56534D01*
X2677814Y-55950D01*
X2677687Y-55450D01*
X2677434Y-55117D01*
X2676990Y-54867D01*
X2675280D01*
Y-59867D01*
X2677370D01*
X2677814Y-59534D01*
X2678067Y-59034D01*
X2678194Y-58450D01*
X2678067Y-57867D01*
X2677687Y-57367D01*
X2677244Y-57200D01*
X2675280D01*
G01X-984580Y-698988D02*
Y4193602D01*
X5868320D01*
Y-698988D01*
X-984580D01*
G01X7723Y-521204D02*
X7253Y-520889D01*
X6705Y-520679D01*
X6078D01*
X5373Y-520994D01*
X4825Y-521519D01*
X4433Y-522149D01*
X4120Y-523199D01*
X4042Y-524144D01*
X4198Y-525089D01*
X4433Y-525719D01*
X4903Y-526349D01*
X5452Y-526769D01*
X6000Y-526979D01*
X6548D01*
X7097Y-526769D01*
X7567Y-526454D01*
X7958Y-526034D01*
G01X11360Y-520679D02*
X13240D01*
G01X12300D02*
Y-526979D01*
G01X11360D02*
X13240D01*
G01X18600Y-520679D02*
Y-526979D01*
G01X16798Y-520679D02*
X20402D01*
G01X24900Y-526979D02*
Y-524144D01*
X23333Y-520679D01*
G01X26467D02*
X24900Y-524144D01*
G01X35777Y-525719D02*
X36247Y-526454D01*
X36873Y-526874D01*
X37578Y-526979D01*
X38205Y-526874D01*
X38832Y-526349D01*
X39223Y-525719D01*
X39302Y-525089D01*
X39145Y-524354D01*
X38597Y-523829D01*
X38048Y-523619D01*
X37343D01*
G01X38048D02*
X38518Y-523304D01*
X38910Y-522779D01*
X39067Y-522149D01*
X38910Y-521519D01*
X38518Y-520994D01*
X37813Y-520679D01*
X37108Y-520784D01*
X36403Y-521204D01*
G01X42077Y-525719D02*
X42547Y-526454D01*
X43173Y-526874D01*
X43878Y-526979D01*
X44505Y-526874D01*
X45132Y-526349D01*
X45523Y-525719D01*
X45602Y-525089D01*
X45445Y-524354D01*
X44897Y-523829D01*
X44348Y-523619D01*
X43643D01*
G01X44348D02*
X44818Y-523304D01*
X45210Y-522779D01*
X45367Y-522149D01*
X45210Y-521519D01*
X44818Y-520994D01*
X44113Y-520679D01*
X43408Y-520784D01*
X42703Y-521204D01*
G01X48377Y-525719D02*
X48847Y-526454D01*
X49473Y-526874D01*
X50178Y-526979D01*
X50805Y-526874D01*
X51432Y-526349D01*
X51823Y-525719D01*
X51902Y-525089D01*
X51745Y-524354D01*
X51197Y-523829D01*
X50648Y-523619D01*
X49943D01*
G01X50648D02*
X51118Y-523304D01*
X51510Y-522779D01*
X51667Y-522149D01*
X51510Y-521519D01*
X51118Y-520994D01*
X50413Y-520679D01*
X49708Y-520784D01*
X49003Y-521204D01*
G01X56243Y-526979D02*
X56400Y-525614D01*
X56635Y-524459D01*
X56948Y-523409D01*
X57340Y-522254D01*
X57967Y-520679D01*
X54833D01*
G01X62543Y-526979D02*
X62700Y-525614D01*
X62935Y-524459D01*
X63248Y-523409D01*
X63640Y-522254D01*
X64267Y-520679D01*
X61133D01*
G01X68843Y-528134D02*
X69157Y-526769D01*
G01X75300Y-520679D02*
Y-526979D01*
G01X73498Y-520679D02*
X77102D01*
G01X79642Y-526979D02*
X81600Y-520679D01*
X83558Y-526979D01*
G01X82853Y-524774D02*
X80347D01*
G01X86960Y-520679D02*
X88840D01*
G01X87900D02*
Y-526979D01*
G01X86960D02*
X88840D01*
G01X91850Y-520679D02*
X92947Y-526979D01*
X94200Y-520679D01*
X95453Y-526979D01*
X96550Y-520679D01*
G01X98542Y-526979D02*
X100500Y-520679D01*
X102458Y-526979D01*
G01X101753Y-524774D02*
X99247D01*
G01X104998Y-526979D02*
Y-520679D01*
X108602Y-526979D01*
Y-520679D01*
G01X119008Y-529079D02*
X118225Y-528029D01*
X117833Y-526979D01*
Y-522779D01*
X118225Y-521729D01*
X119008Y-520679D01*
G01X130433Y-526979D02*
Y-520679D01*
X132392D01*
X133018Y-520994D01*
X133410Y-521414D01*
X133567Y-522254D01*
X133410Y-523094D01*
X132940Y-523619D01*
X132392Y-523934D01*
X130433D01*
G01X132392D02*
X133567Y-526979D01*
G01X138300Y-527189D02*
X138143Y-527084D01*
Y-526874D01*
X138300Y-526769D01*
X138457Y-526874D01*
Y-527084D01*
X138300Y-527189D01*
G01X144600Y-526979D02*
X143973Y-526874D01*
X143425Y-526454D01*
X142955Y-525824D01*
X142642Y-525089D01*
X142485Y-524249D01*
Y-523409D01*
X142642Y-522569D01*
X142955Y-521834D01*
X143425Y-521204D01*
X143973Y-520784D01*
X144600Y-520679D01*
X145227Y-520784D01*
X145775Y-521204D01*
X146245Y-521834D01*
X146558Y-522569D01*
X146715Y-523409D01*
Y-524249D01*
X146558Y-525089D01*
X146245Y-525824D01*
X145775Y-526454D01*
X145227Y-526874D01*
X144600Y-526979D01*
G01X150900Y-527189D02*
X150743Y-527084D01*
Y-526874D01*
X150900Y-526769D01*
X151057Y-526874D01*
Y-527084D01*
X150900Y-527189D01*
G01X158923Y-521204D02*
X158453Y-520889D01*
X157905Y-520679D01*
X157278D01*
X156573Y-520994D01*
X156025Y-521519D01*
X155633Y-522149D01*
X155320Y-523199D01*
X155242Y-524144D01*
X155398Y-525089D01*
X155633Y-525719D01*
X156103Y-526349D01*
X156652Y-526769D01*
X157200Y-526979D01*
X157748D01*
X158297Y-526769D01*
X158767Y-526454D01*
X159158Y-526034D01*
G01X163500Y-527189D02*
X163343Y-527084D01*
Y-526874D01*
X163500Y-526769D01*
X163657Y-526874D01*
Y-527084D01*
X163500Y-527189D01*
G01X170192Y-529079D02*
X170975Y-528029D01*
X171367Y-526979D01*
Y-522779D01*
X170975Y-521729D01*
X170192Y-520679D01*
G01X6470Y-513829D02*
X8037D01*
Y-515719D01*
X7567Y-516349D01*
X7018Y-516769D01*
X6235Y-516979D01*
X5452Y-516769D01*
X4903Y-516349D01*
X4433Y-515719D01*
X4120Y-514984D01*
X3963Y-514144D01*
Y-513409D01*
X4120Y-512779D01*
X4433Y-512044D01*
X4903Y-511414D01*
X5373Y-510994D01*
X6000Y-510679D01*
X6548D01*
X7175Y-510889D01*
X7645Y-511309D01*
G01X10577Y-510679D02*
Y-515194D01*
X10890Y-516139D01*
X11517Y-516769D01*
X12300Y-516979D01*
X13083Y-516769D01*
X13710Y-516139D01*
X14023Y-515194D01*
Y-510679D01*
G01X17660D02*
X19540D01*
G01X18600D02*
Y-516979D01*
G01X17660D02*
X19540D01*
G01X23255Y-516139D02*
X23882Y-516664D01*
X24587Y-516979D01*
X25213D01*
X25840Y-516664D01*
X26310Y-516139D01*
X26545Y-515404D01*
X26388Y-514669D01*
X25997Y-514039D01*
X25292Y-513619D01*
X24352Y-513409D01*
X23803Y-512989D01*
X23568Y-512254D01*
X23725Y-511519D01*
X24117Y-510994D01*
X24665Y-510679D01*
X25213D01*
X25762Y-510889D01*
X26232Y-511414D01*
G01X29555Y-516979D02*
Y-510679D01*
G01X32845D02*
Y-516979D01*
G01Y-513829D02*
X29555D01*
G01X35542Y-516979D02*
X37500Y-510679D01*
X39458Y-516979D01*
G01X38753Y-514774D02*
X36247D01*
G01X41998Y-516979D02*
Y-510679D01*
X45602Y-516979D01*
Y-510679D01*
G01X54677Y-516979D02*
Y-510679D01*
X56243D01*
X56870Y-510994D01*
X57340Y-511414D01*
X57732Y-512044D01*
X58045Y-512779D01*
X58123Y-513829D01*
X58045Y-514879D01*
X57732Y-515614D01*
X57340Y-516244D01*
X56870Y-516664D01*
X56243Y-516979D01*
X54677D01*
G01X61760Y-510679D02*
X63640D01*
G01X62700D02*
Y-516979D01*
G01X61760D02*
X63640D01*
G01X67355Y-516139D02*
X67982Y-516664D01*
X68687Y-516979D01*
X69313D01*
X69940Y-516664D01*
X70410Y-516139D01*
X70645Y-515404D01*
X70488Y-514669D01*
X70097Y-514039D01*
X69392Y-513619D01*
X68452Y-513409D01*
X67903Y-512989D01*
X67668Y-512254D01*
X67825Y-511519D01*
X68217Y-510994D01*
X68765Y-510679D01*
X69313D01*
X69862Y-510889D01*
X70332Y-511414D01*
G01X75300Y-510679D02*
Y-516979D01*
G01X73498Y-510679D02*
X77102D01*
G01X81600Y-517189D02*
X81443Y-517084D01*
Y-516874D01*
X81600Y-516769D01*
X81757Y-516874D01*
Y-517084D01*
X81600Y-517189D01*
G01X87743Y-518134D02*
X88057Y-516769D01*
G01X94200Y-510679D02*
Y-516979D01*
G01X92398Y-510679D02*
X96002D01*
G01X98542Y-516979D02*
X100500Y-510679D01*
X102458Y-516979D01*
G01X101753Y-514774D02*
X99247D01*
G01X106800Y-516979D02*
X106173Y-516874D01*
X105625Y-516454D01*
X105155Y-515824D01*
X104842Y-515089D01*
X104685Y-514249D01*
Y-513409D01*
X104842Y-512569D01*
X105155Y-511834D01*
X105625Y-511204D01*
X106173Y-510784D01*
X106800Y-510679D01*
X107427Y-510784D01*
X107975Y-511204D01*
X108445Y-511834D01*
X108758Y-512569D01*
X108915Y-513409D01*
Y-514249D01*
X108758Y-515089D01*
X108445Y-515824D01*
X107975Y-516454D01*
X107427Y-516874D01*
X106800Y-516979D01*
G01X113100D02*
Y-514144D01*
X111533Y-510679D01*
G01X114667D02*
X113100Y-514144D01*
G01X117677Y-510679D02*
Y-515194D01*
X117990Y-516139D01*
X118617Y-516769D01*
X119400Y-516979D01*
X120183Y-516769D01*
X120810Y-516139D01*
X121123Y-515194D01*
Y-510679D01*
G01X123742Y-516979D02*
X125700Y-510679D01*
X127658Y-516979D01*
G01X126953Y-514774D02*
X124447D01*
G01X130198Y-516979D02*
Y-510679D01*
X133802Y-516979D01*
Y-510679D01*
G01X4198Y-506979D02*
Y-500679D01*
X7802Y-506979D01*
Y-500679D01*
G01X12300Y-506979D02*
X11673Y-506874D01*
X11125Y-506454D01*
X10655Y-505824D01*
X10342Y-505089D01*
X10185Y-504249D01*
Y-503409D01*
X10342Y-502569D01*
X10655Y-501834D01*
X11125Y-501204D01*
X11673Y-500784D01*
X12300Y-500679D01*
X12927Y-500784D01*
X13475Y-501204D01*
X13945Y-501834D01*
X14258Y-502569D01*
X14415Y-503409D01*
Y-504249D01*
X14258Y-505089D01*
X13945Y-505824D01*
X13475Y-506454D01*
X12927Y-506874D01*
X12300Y-506979D01*
G01X18600Y-507189D02*
X18443Y-507084D01*
Y-506874D01*
X18600Y-506769D01*
X18757Y-506874D01*
Y-507084D01*
X18600Y-507189D01*
G01X23412Y-501729D02*
X23882Y-501099D01*
X24430Y-500784D01*
X25057Y-500679D01*
X25840Y-500889D01*
X26388Y-501414D01*
X26545Y-502044D01*
X26467Y-502674D01*
X26153Y-503199D01*
X24587Y-504249D01*
X23882Y-504984D01*
X23412Y-506034D01*
X23255Y-506979D01*
X26545D01*
G01X31200D02*
Y-500679D01*
X30260Y-501939D01*
G01Y-506979D02*
X32140D01*
G01X37500D02*
Y-500679D01*
X36560Y-501939D01*
G01Y-506979D02*
X38440D01*
G01X43643Y-508134D02*
X43957Y-506769D01*
G01X47750Y-500679D02*
X48847Y-506979D01*
X50100Y-500679D01*
X51353Y-506979D01*
X52450Y-500679D01*
G01X57967Y-506979D02*
X54833D01*
Y-500679D01*
X57967D01*
G01X56713Y-503724D02*
X54833D01*
G01X60898Y-506979D02*
Y-500679D01*
X64502Y-506979D01*
Y-500679D01*
G01X67355Y-506979D02*
Y-500679D01*
G01X70645D02*
Y-506979D01*
G01Y-503829D02*
X67355D01*
G01X73577Y-500679D02*
Y-505194D01*
X73890Y-506139D01*
X74517Y-506769D01*
X75300Y-506979D01*
X76083Y-506769D01*
X76710Y-506139D01*
X77023Y-505194D01*
Y-500679D01*
G01X79642Y-506979D02*
X81600Y-500679D01*
X83558Y-506979D01*
G01X82853Y-504774D02*
X80347D01*
G01X92712Y-501729D02*
X93182Y-501099D01*
X93730Y-500784D01*
X94357Y-500679D01*
X95140Y-500889D01*
X95688Y-501414D01*
X95845Y-502044D01*
X95767Y-502674D01*
X95453Y-503199D01*
X93887Y-504249D01*
X93182Y-504984D01*
X92712Y-506034D01*
X92555Y-506979D01*
X95845D01*
G01X98698D02*
Y-500679D01*
X102302Y-506979D01*
Y-500679D01*
G01X105077Y-506979D02*
Y-500679D01*
X106643D01*
X107270Y-500994D01*
X107740Y-501414D01*
X108132Y-502044D01*
X108445Y-502779D01*
X108523Y-503829D01*
X108445Y-504879D01*
X108132Y-505614D01*
X107740Y-506244D01*
X107270Y-506664D01*
X106643Y-506979D01*
X105077D01*
G01X117833D02*
Y-500679D01*
X119792D01*
X120418Y-500994D01*
X120810Y-501414D01*
X120967Y-502254D01*
X120810Y-503094D01*
X120340Y-503619D01*
X119792Y-503934D01*
X117833D01*
G01X119792D02*
X120967Y-506979D01*
G01X123977D02*
Y-500679D01*
X125543D01*
X126170Y-500994D01*
X126640Y-501414D01*
X127032Y-502044D01*
X127345Y-502779D01*
X127423Y-503829D01*
X127345Y-504879D01*
X127032Y-505614D01*
X126640Y-506244D01*
X126170Y-506664D01*
X125543Y-506979D01*
X123977D01*
G01X132000Y-507189D02*
X131843Y-507084D01*
Y-506874D01*
X132000Y-506769D01*
X132157Y-506874D01*
Y-507084D01*
X132000Y-507189D01*
G01X28300Y-494279D02*
X25780Y-493862D01*
X23575Y-492196D01*
X21685Y-489696D01*
X20425Y-486779D01*
X19795Y-483446D01*
Y-480112D01*
X20425Y-476779D01*
X21685Y-473862D01*
X23575Y-471363D01*
X25780Y-469696D01*
X28300Y-469279D01*
X30820Y-469696D01*
X33025Y-471363D01*
X34915Y-473862D01*
X36175Y-476779D01*
X36805Y-480112D01*
Y-483446D01*
X36175Y-486779D01*
X34915Y-489696D01*
X33025Y-492196D01*
X30820Y-493862D01*
X28300Y-494279D01*
G01X30820Y-487612D02*
X34600Y-494279D01*
G01X48145Y-477613D02*
Y-489279D01*
X49405Y-492196D01*
X51295Y-493862D01*
X53500Y-494279D01*
X55705Y-493862D01*
X57595Y-492196D01*
X58855Y-489279D01*
G01Y-494279D02*
Y-477613D01*
G01X84370Y-494279D02*
Y-477613D01*
G01Y-480529D02*
X83110Y-478863D01*
X81220Y-478029D01*
X79015Y-477613D01*
X76810Y-478446D01*
X74920Y-480112D01*
X73660Y-482613D01*
X73030Y-485946D01*
X73660Y-489279D01*
X74920Y-491780D01*
X76810Y-493446D01*
X79015Y-494279D01*
X81220Y-493862D01*
X83110Y-492613D01*
X84370Y-490946D01*
G01X98545Y-494279D02*
Y-477613D01*
G01Y-481779D02*
X99805Y-479696D01*
X101695Y-478029D01*
X104215Y-477613D01*
X106420Y-478029D01*
X108310Y-479696D01*
X109255Y-482613D01*
Y-494279D01*
G01X129100Y-469279D02*
Y-494279D01*
G01X124690Y-477613D02*
X133510D01*
G01X159970Y-494279D02*
Y-477613D01*
G01Y-480529D02*
X158710Y-478863D01*
X156820Y-478029D01*
X154615Y-477613D01*
X152410Y-478446D01*
X150520Y-480112D01*
X149260Y-482613D01*
X148630Y-485946D01*
X149260Y-489279D01*
X150520Y-491780D01*
X152410Y-493446D01*
X154615Y-494279D01*
X156820Y-493862D01*
X158710Y-492613D01*
X159970Y-490946D01*
G01X25935Y-29134D02*
G03I-6250J0D01*
G01Y1803261D02*
G03I-6250J0D01*
G01X53149Y-29134D02*
G03I-5905J0D01*
G01X199650Y-473979D02*
Y-481979D01*
X203650D01*
G01X211450D02*
Y-476646D01*
G01Y-477579D02*
X211050Y-477046D01*
X210450Y-476779D01*
X209750Y-476646D01*
X209050Y-476912D01*
X208450Y-477446D01*
X208050Y-478246D01*
X207850Y-479312D01*
X208050Y-480379D01*
X208450Y-481179D01*
X209050Y-481712D01*
X209750Y-481979D01*
X210450Y-481846D01*
X211050Y-481446D01*
X211450Y-480913D01*
G01X215550Y-484379D02*
X216150Y-484646D01*
X216950Y-484379D01*
X217450Y-483846D01*
X217850Y-483179D01*
X218450Y-481046D01*
X219750Y-476646D01*
G01X216550D02*
X218450Y-481046D01*
G01X224150Y-478379D02*
X227350D01*
X227050Y-477446D01*
X226550Y-476912D01*
X225850Y-476646D01*
X225150Y-476779D01*
X224550Y-477179D01*
X224150Y-478112D01*
X223950Y-478913D01*
Y-479712D01*
X224150Y-480512D01*
X224650Y-481312D01*
X225250Y-481846D01*
X225950Y-481979D01*
X226650Y-481712D01*
X227350Y-480913D01*
G01X232250Y-481979D02*
Y-476646D01*
G01Y-477712D02*
X232750Y-477179D01*
X233250Y-476779D01*
X233950Y-476646D01*
X234450Y-476779D01*
X235050Y-477179D01*
G01X223350Y-531979D02*
Y-523979D01*
X227950Y-531979D01*
Y-523979D01*
G01X233650Y-526646D02*
Y-531979D01*
G01Y-524512D02*
X233450Y-524379D01*
Y-524112D01*
X233650Y-523979D01*
X233850Y-524112D01*
Y-524379D01*
X233650Y-524512D01*
G01X239950Y-531979D02*
Y-526646D01*
G01Y-527979D02*
X240350Y-527312D01*
X240950Y-526779D01*
X241750Y-526646D01*
X242450Y-526779D01*
X243050Y-527312D01*
X243350Y-528246D01*
Y-531979D01*
G01X251450D02*
Y-526646D01*
G01Y-527579D02*
X251050Y-527046D01*
X250450Y-526779D01*
X249750Y-526646D01*
X249050Y-526912D01*
X248450Y-527446D01*
X248050Y-528246D01*
X247850Y-529312D01*
X248050Y-530379D01*
X248450Y-531179D01*
X249050Y-531712D01*
X249750Y-531979D01*
X250450Y-531846D01*
X251050Y-531446D01*
X251450Y-530913D01*
G01X212179Y-508436D02*
Y-500436D01*
X214579D01*
X215379Y-500836D01*
X215979Y-501769D01*
X216179Y-502836D01*
X215979Y-503903D01*
X215479Y-504703D01*
X214579Y-505103D01*
X212179D01*
G01X219679Y-508436D02*
X222179Y-500436D01*
X224679Y-508436D01*
G01X223779Y-505636D02*
X220579D01*
G01X227879Y-508436D02*
Y-500436D01*
X232479Y-508436D01*
Y-500436D01*
G01X240179Y-508436D02*
X236179D01*
Y-500436D01*
X240179D01*
G01X238579Y-504303D02*
X236179D01*
G01X244179Y-500436D02*
Y-508436D01*
X248179D01*
G01X326250Y-525312D02*
X326850Y-524512D01*
X327550Y-524112D01*
X328350Y-523979D01*
X329350Y-524246D01*
X330050Y-524912D01*
X330250Y-525712D01*
X330150Y-526513D01*
X329750Y-527179D01*
X327750Y-528512D01*
X326850Y-529446D01*
X326250Y-530779D01*
X326050Y-531979D01*
X330250D01*
G01X336150Y-523979D02*
X335350Y-524246D01*
X334750Y-524912D01*
X334350Y-525712D01*
X334050Y-526779D01*
X333950Y-527979D01*
X334050Y-529179D01*
X334350Y-530246D01*
X334750Y-531046D01*
X335350Y-531712D01*
X336150Y-531979D01*
X336950Y-531712D01*
X337550Y-531046D01*
X337950Y-530246D01*
X338250Y-529179D01*
X338350Y-527979D01*
X338250Y-526779D01*
X337950Y-525712D01*
X337550Y-524912D01*
X336950Y-524246D01*
X336150Y-523979D01*
G01X342250Y-525312D02*
X342850Y-524512D01*
X343550Y-524112D01*
X344350Y-523979D01*
X345350Y-524246D01*
X346050Y-524912D01*
X346250Y-525712D01*
X346150Y-526513D01*
X345750Y-527179D01*
X343750Y-528512D01*
X342850Y-529446D01*
X342250Y-530779D01*
X342050Y-531979D01*
X346250D01*
G01X349950Y-530379D02*
X350550Y-531312D01*
X351350Y-531846D01*
X352250Y-531979D01*
X353050Y-531846D01*
X353850Y-531179D01*
X354350Y-530379D01*
X354450Y-529579D01*
X354250Y-528646D01*
X353550Y-527979D01*
X352850Y-527712D01*
X351950D01*
G01X352850D02*
X353450Y-527312D01*
X353950Y-526646D01*
X354150Y-525846D01*
X353950Y-525046D01*
X353450Y-524379D01*
X352550Y-523979D01*
X351650Y-524112D01*
X350750Y-524646D01*
G01X358350Y-532246D02*
X361950Y-523979D01*
G01X368150D02*
X367350Y-524246D01*
X366750Y-524912D01*
X366350Y-525712D01*
X366050Y-526779D01*
X365950Y-527979D01*
X366050Y-529179D01*
X366350Y-530246D01*
X366750Y-531046D01*
X367350Y-531712D01*
X368150Y-531979D01*
X368950Y-531712D01*
X369550Y-531046D01*
X369950Y-530246D01*
X370250Y-529179D01*
X370350Y-527979D01*
X370250Y-526779D01*
X369950Y-525712D01*
X369550Y-524912D01*
X368950Y-524246D01*
X368150Y-523979D01*
G01X373950Y-530379D02*
X374550Y-531312D01*
X375350Y-531846D01*
X376250Y-531979D01*
X377050Y-531846D01*
X377850Y-531179D01*
X378350Y-530379D01*
X378450Y-529579D01*
X378250Y-528646D01*
X377550Y-527979D01*
X376850Y-527712D01*
X375950D01*
G01X376850D02*
X377450Y-527312D01*
X377950Y-526646D01*
X378150Y-525846D01*
X377950Y-525046D01*
X377450Y-524379D01*
X376550Y-523979D01*
X375650Y-524112D01*
X374750Y-524646D01*
G01X382350Y-532246D02*
X385950Y-523979D01*
G01X390250Y-525312D02*
X390850Y-524512D01*
X391550Y-524112D01*
X392350Y-523979D01*
X393350Y-524246D01*
X394050Y-524912D01*
X394250Y-525712D01*
X394150Y-526513D01*
X393750Y-527179D01*
X391750Y-528512D01*
X390850Y-529446D01*
X390250Y-530779D01*
X390050Y-531979D01*
X394250D01*
G01X401350D02*
Y-523979D01*
X397650Y-529712D01*
X402650D01*
G01X325950Y-506979D02*
Y-498979D01*
X327950D01*
X328750Y-499379D01*
X329350Y-499912D01*
X329850Y-500712D01*
X330250Y-501646D01*
X330350Y-502979D01*
X330250Y-504312D01*
X329850Y-505246D01*
X329350Y-506046D01*
X328750Y-506579D01*
X327950Y-506979D01*
X325950D01*
G01X333650D02*
X336150Y-498979D01*
X338650Y-506979D01*
G01X337750Y-504179D02*
X334550D01*
G01X344150Y-498979D02*
X343350Y-499246D01*
X342750Y-499912D01*
X342350Y-500712D01*
X342050Y-501779D01*
X341950Y-502979D01*
X342050Y-504179D01*
X342350Y-505246D01*
X342750Y-506046D01*
X343350Y-506712D01*
X344150Y-506979D01*
X344950Y-506712D01*
X345550Y-506046D01*
X345950Y-505246D01*
X346250Y-504179D01*
X346350Y-502979D01*
X346250Y-501779D01*
X345950Y-500712D01*
X345550Y-499912D01*
X344950Y-499246D01*
X344150Y-498979D01*
G01X350250Y-506979D02*
Y-498979D01*
X354050D01*
G01X352650Y-502846D02*
X350250D01*
G01X360150Y-498979D02*
X359350Y-499246D01*
X358750Y-499912D01*
X358350Y-500712D01*
X358050Y-501779D01*
X357950Y-502979D01*
X358050Y-504179D01*
X358350Y-505246D01*
X358750Y-506046D01*
X359350Y-506712D01*
X360150Y-506979D01*
X360950Y-506712D01*
X361550Y-506046D01*
X361950Y-505246D01*
X362250Y-504179D01*
X362350Y-502979D01*
X362250Y-501779D01*
X361950Y-500712D01*
X361550Y-499912D01*
X360950Y-499246D01*
X360150Y-498979D01*
G01X368150D02*
Y-506979D01*
G01X365850Y-498979D02*
X370450D01*
G01X373550Y-506979D02*
Y-498979D01*
X376150Y-505646D01*
X378750Y-498979D01*
Y-506979D01*
G01X384950Y-502712D02*
X385350Y-502312D01*
X385650Y-501646D01*
X385850Y-500712D01*
X385650Y-499912D01*
X385250Y-499379D01*
X384550Y-498979D01*
X381850D01*
Y-506979D01*
X385150D01*
X385850Y-506446D01*
X386250Y-505646D01*
X386450Y-504712D01*
X386250Y-503779D01*
X385650Y-502979D01*
X384950Y-502712D01*
X381850D01*
G01X390950Y-498979D02*
X393350D01*
G01X392150D02*
Y-506979D01*
G01X390950D02*
X393350D01*
G01X398150Y-505379D02*
X398650Y-506179D01*
X399250Y-506712D01*
X399950Y-506979D01*
X400750Y-506712D01*
X401350Y-506179D01*
X401950Y-505379D01*
X402150Y-504312D01*
Y-498979D01*
G01X408150D02*
X407350Y-499246D01*
X406750Y-499912D01*
X406350Y-500712D01*
X406050Y-501779D01*
X405950Y-502979D01*
X406050Y-504179D01*
X406350Y-505246D01*
X406750Y-506046D01*
X407350Y-506712D01*
X408150Y-506979D01*
X408950Y-506712D01*
X409550Y-506046D01*
X409950Y-505246D01*
X410250Y-504179D01*
X410350Y-502979D01*
X410250Y-501779D01*
X409950Y-500712D01*
X409550Y-499912D01*
X408950Y-499246D01*
X408150Y-498979D01*
G01X343750Y-481979D02*
Y-473979D01*
X347550D01*
G01X346150Y-477846D02*
X343750D01*
G01X353650Y-473979D02*
X352850Y-474246D01*
X352250Y-474912D01*
X351850Y-475712D01*
X351550Y-476779D01*
X351450Y-477979D01*
X351550Y-479179D01*
X351850Y-480246D01*
X352250Y-481046D01*
X352850Y-481712D01*
X353650Y-481979D01*
X354450Y-481712D01*
X355050Y-481046D01*
X355450Y-480246D01*
X355750Y-479179D01*
X355850Y-477979D01*
X355750Y-476779D01*
X355450Y-475712D01*
X355050Y-474912D01*
X354450Y-474246D01*
X353650Y-473979D01*
G01X361650D02*
Y-481979D01*
G01X359350Y-473979D02*
X363950D01*
G01X366650Y-484646D02*
X372650D01*
G01X375050Y-481979D02*
Y-473979D01*
X377650Y-480646D01*
X380250Y-473979D01*
Y-481979D01*
G01X386450Y-477712D02*
X386850Y-477312D01*
X387150Y-476646D01*
X387350Y-475712D01*
X387150Y-474912D01*
X386750Y-474379D01*
X386050Y-473979D01*
X383350D01*
Y-481979D01*
X386650D01*
X387350Y-481446D01*
X387750Y-480646D01*
X387950Y-479712D01*
X387750Y-478779D01*
X387150Y-477979D01*
X386450Y-477712D01*
X383350D01*
G01X390650Y-484646D02*
X396650D01*
G01X403650Y-481979D02*
X399650D01*
Y-473979D01*
X403650D01*
G01X402050Y-477846D02*
X399650D01*
G01X407050Y-481979D02*
Y-473979D01*
X409650Y-480646D01*
X412250Y-473979D01*
Y-481979D01*
G01X417650D02*
X418350Y-481846D01*
X419150Y-481446D01*
X419650Y-480779D01*
X419850Y-479846D01*
X419650Y-478913D01*
X419050Y-478112D01*
X418150Y-477712D01*
X417150D01*
X416550Y-477446D01*
X416050Y-476779D01*
X415850Y-475846D01*
X416150Y-474912D01*
X416850Y-474246D01*
X417650Y-473979D01*
X418450Y-474246D01*
X419150Y-474912D01*
X419450Y-475846D01*
X419250Y-476779D01*
X418750Y-477446D01*
X418150Y-477712D01*
X417150D01*
X416250Y-478112D01*
X415650Y-478913D01*
X415450Y-479846D01*
X415650Y-480779D01*
X416150Y-481446D01*
X416950Y-481846D01*
X417650Y-481979D01*
G01X423950Y-481046D02*
X424650Y-481712D01*
X425450Y-481979D01*
X426250Y-481712D01*
X426950Y-480913D01*
X427450Y-479712D01*
X427650Y-478512D01*
Y-477046D01*
X427450Y-475846D01*
X426950Y-474779D01*
X426350Y-474246D01*
X425650Y-473979D01*
X424850Y-474246D01*
X424250Y-474779D01*
X423850Y-475579D01*
X423650Y-476646D01*
X423850Y-477579D01*
X424350Y-478512D01*
X424950Y-479046D01*
X425650Y-479179D01*
X426450Y-478913D01*
X427050Y-478246D01*
X427650Y-477046D01*
G01X433650Y-473979D02*
X432850Y-474246D01*
X432250Y-474912D01*
X431850Y-475712D01*
X431550Y-476779D01*
X431450Y-477979D01*
X431550Y-479179D01*
X431850Y-480246D01*
X432250Y-481046D01*
X432850Y-481712D01*
X433650Y-481979D01*
X434450Y-481712D01*
X435050Y-481046D01*
X435450Y-480246D01*
X435750Y-479179D01*
X435850Y-477979D01*
X435750Y-476779D01*
X435450Y-475712D01*
X435050Y-474912D01*
X434450Y-474246D01*
X433650Y-473979D01*
G01X439450Y-481979D02*
Y-473979D01*
G01X443250D02*
X439450Y-478913D01*
G01X443850Y-481979D02*
X441150Y-476646D01*
G01X414650Y-534979D02*
Y-526979D01*
X413450Y-528579D01*
G01Y-534979D02*
X415850D01*
G01X420750Y-531646D02*
X421450Y-530712D01*
X422050Y-530179D01*
X422850Y-529912D01*
X423550Y-530179D01*
X424050Y-530712D01*
X424450Y-531512D01*
X424550Y-532446D01*
X424450Y-533246D01*
X424050Y-534046D01*
X423450Y-534712D01*
X422750Y-534979D01*
X421950Y-534712D01*
X421250Y-533913D01*
X420850Y-532712D01*
X420750Y-531379D01*
X420950Y-529646D01*
X421250Y-528712D01*
X421750Y-527779D01*
X422450Y-527112D01*
X423150Y-526979D01*
X423850Y-527246D01*
X424350Y-527912D01*
G01X430650Y-535246D02*
X430450Y-535112D01*
Y-534846D01*
X430650Y-534712D01*
X430850Y-534846D01*
Y-535112D01*
X430650Y-535246D01*
G01X436750Y-531646D02*
X437450Y-530712D01*
X438050Y-530179D01*
X438850Y-529912D01*
X439550Y-530179D01*
X440050Y-530712D01*
X440450Y-531512D01*
X440550Y-532446D01*
X440450Y-533246D01*
X440050Y-534046D01*
X439450Y-534712D01*
X438750Y-534979D01*
X437950Y-534712D01*
X437250Y-533913D01*
X436850Y-532712D01*
X436750Y-531379D01*
X436950Y-529646D01*
X437250Y-528712D01*
X437750Y-527779D01*
X438450Y-527112D01*
X439150Y-526979D01*
X439850Y-527246D01*
X440350Y-527912D01*
G01X459650Y-534979D02*
Y-526979D01*
X458450Y-528579D01*
G01Y-534979D02*
X460850D01*
G01X467450D02*
X467650Y-533246D01*
X467950Y-531779D01*
X468350Y-530446D01*
X468850Y-528979D01*
X469650Y-526979D01*
X465650D01*
G01X475650Y-535246D02*
X475450Y-535112D01*
Y-534846D01*
X475650Y-534712D01*
X475850Y-534846D01*
Y-535112D01*
X475650Y-535246D01*
G01X481750Y-528312D02*
X482350Y-527512D01*
X483050Y-527112D01*
X483850Y-526979D01*
X484850Y-527246D01*
X485550Y-527912D01*
X485750Y-528712D01*
X485650Y-529513D01*
X485250Y-530179D01*
X483250Y-531512D01*
X482350Y-532446D01*
X481750Y-533779D01*
X481550Y-534979D01*
X485750D01*
G01X479650Y-508379D02*
X480150Y-509179D01*
X480750Y-509712D01*
X481450Y-509979D01*
X482250Y-509712D01*
X482850Y-509179D01*
X483450Y-508379D01*
X483650Y-507312D01*
Y-501979D01*
G01X1004442Y1879613D02*
X1005372Y1880862D01*
X1006457Y1881488D01*
X1007697Y1881696D01*
X1009247Y1881279D01*
X1010332Y1880238D01*
X1010642Y1878988D01*
X1010487Y1877737D01*
X1009867Y1876696D01*
X1006767Y1874613D01*
X1005372Y1873154D01*
X1004442Y1871071D01*
X1004132Y1869196D01*
X1010642D01*
G01X1019787D02*
Y1881696D01*
X1017927Y1879196D01*
G01Y1869196D02*
X1021647D01*
G01X1032187Y1881696D02*
X1030947Y1881279D01*
X1030017Y1880238D01*
X1029397Y1878988D01*
X1028932Y1877321D01*
X1028777Y1875446D01*
X1028932Y1873571D01*
X1029397Y1871904D01*
X1030017Y1870654D01*
X1030947Y1869613D01*
X1032187Y1869196D01*
X1033427Y1869613D01*
X1034357Y1870654D01*
X1034977Y1871904D01*
X1035442Y1873571D01*
X1035597Y1875446D01*
X1035442Y1877321D01*
X1034977Y1878988D01*
X1034357Y1880238D01*
X1033427Y1881279D01*
X1032187Y1881696D01*
G01X1044587Y1869196D02*
Y1881696D01*
X1042727Y1879196D01*
G01Y1869196D02*
X1046447D01*
G01X1053577Y1871071D02*
X1054507Y1870029D01*
X1055592Y1869404D01*
X1056987Y1869196D01*
X1058382Y1869613D01*
X1059467Y1870446D01*
X1060242Y1871904D01*
X1060397Y1873571D01*
X1060087Y1875238D01*
X1059312Y1876279D01*
X1058227Y1877113D01*
X1057142Y1877321D01*
X1056057Y1877113D01*
X1054662Y1876279D01*
X1055127Y1881696D01*
X1059312D01*
G01X1069387Y1868779D02*
X1069077Y1868988D01*
Y1869404D01*
X1069387Y1869613D01*
X1069697Y1869404D01*
Y1868988D01*
X1069387Y1868779D01*
G01X1081477Y1869196D02*
X1081787Y1871904D01*
X1082252Y1874196D01*
X1082872Y1876279D01*
X1083647Y1878571D01*
X1084887Y1881696D01*
X1078687D01*
G01X1096047Y1869196D02*
Y1881696D01*
X1090312Y1872738D01*
X1098062D01*
G01X1022727Y1846071D02*
X1023657Y1845029D01*
X1024742Y1844404D01*
X1026137Y1844196D01*
X1027532Y1844613D01*
X1028617Y1845446D01*
X1029392Y1846904D01*
X1029547Y1848571D01*
X1029237Y1850238D01*
X1028462Y1851279D01*
X1027377Y1852113D01*
X1026292Y1852321D01*
X1025207Y1852113D01*
X1023812Y1851279D01*
X1024277Y1856696D01*
X1028462D01*
G01X1035127Y1846696D02*
X1036057Y1845237D01*
X1037297Y1844404D01*
X1038692Y1844196D01*
X1039932Y1844404D01*
X1041172Y1845446D01*
X1041947Y1846696D01*
X1042102Y1847946D01*
X1041792Y1849404D01*
X1040707Y1850446D01*
X1039622Y1850863D01*
X1038227D01*
G01X1039622D02*
X1040552Y1851488D01*
X1041327Y1852529D01*
X1041637Y1853779D01*
X1041327Y1855029D01*
X1040552Y1856071D01*
X1039157Y1856696D01*
X1037762Y1856488D01*
X1036367Y1855654D01*
G01X1047527Y1846696D02*
X1048457Y1845237D01*
X1049697Y1844404D01*
X1051092Y1844196D01*
X1052332Y1844404D01*
X1053572Y1845446D01*
X1054347Y1846696D01*
X1054502Y1847946D01*
X1054192Y1849404D01*
X1053107Y1850446D01*
X1052022Y1850863D01*
X1050627D01*
G01X1052022D02*
X1052952Y1851488D01*
X1053727Y1852529D01*
X1054037Y1853779D01*
X1053727Y1855029D01*
X1052952Y1856071D01*
X1051557Y1856696D01*
X1050162Y1856488D01*
X1048767Y1855654D01*
G01X1063337Y1843779D02*
X1063027Y1843988D01*
Y1844404D01*
X1063337Y1844613D01*
X1063647Y1844404D01*
Y1843988D01*
X1063337Y1843779D01*
G01X1075737Y1844196D02*
X1076822Y1844404D01*
X1078062Y1845029D01*
X1078837Y1846071D01*
X1079147Y1847529D01*
X1078837Y1848987D01*
X1077907Y1850238D01*
X1076512Y1850863D01*
X1074962D01*
X1074032Y1851279D01*
X1073257Y1852321D01*
X1072947Y1853779D01*
X1073412Y1855238D01*
X1074497Y1856279D01*
X1075737Y1856696D01*
X1076977Y1856279D01*
X1078062Y1855238D01*
X1078527Y1853779D01*
X1078217Y1852321D01*
X1077442Y1851279D01*
X1076512Y1850863D01*
X1074962D01*
X1073567Y1850238D01*
X1072637Y1848987D01*
X1072327Y1847529D01*
X1072637Y1846071D01*
X1073412Y1845029D01*
X1074652Y1844404D01*
X1075737Y1844196D01*
G01X1796457Y1803261D02*
G03I-5906J0D01*
G01X1844045Y-29134D02*
G03I-6250J0D01*
G01Y1803261D02*
G03I-6250J0D01*
G01X2040551D02*
G03I-5906J0D01*
G01X2058974Y1248838D02*
Y1253518D01*
G01Y1251178D02*
X2074574D01*
G01Y1248838D02*
Y1253518D01*
G01X2072494Y1264983D02*
X2073794Y1266543D01*
X2074574Y1268298D01*
Y1269858D01*
X2073794Y1271418D01*
X2072494Y1272588D01*
X2070674Y1273173D01*
X2068854Y1272783D01*
X2067294Y1271808D01*
X2066254Y1270053D01*
X2065734Y1267713D01*
X2064694Y1266348D01*
X2062874Y1265763D01*
X2061054Y1266153D01*
X2059754Y1267128D01*
X2058974Y1268493D01*
Y1269858D01*
X2059494Y1271223D01*
X2060794Y1272393D01*
G01X2058974Y1286978D02*
X2074574D01*
G01X2058974Y1282493D02*
Y1291463D01*
G01X2066774Y1323948D02*
Y1327848D01*
X2071454D01*
X2073014Y1326678D01*
X2074054Y1325313D01*
X2074574Y1323363D01*
X2074054Y1321413D01*
X2073014Y1320048D01*
X2071454Y1318878D01*
X2069634Y1318098D01*
X2067554Y1317708D01*
X2065734D01*
X2064174Y1318098D01*
X2062354Y1318878D01*
X2060794Y1320048D01*
X2059754Y1321218D01*
X2058974Y1322778D01*
Y1324143D01*
X2059494Y1325703D01*
X2060534Y1326873D01*
G01X2074574Y1344578D02*
Y1336778D01*
X2058974D01*
Y1344578D01*
G01X2066514Y1341458D02*
Y1336778D01*
G01X2074574Y1354678D02*
X2058974D01*
Y1359553D01*
X2059754Y1361113D01*
X2060794Y1362088D01*
X2062874Y1362478D01*
X2064954Y1362088D01*
X2066254Y1360918D01*
X2067034Y1359553D01*
Y1354678D01*
G01Y1359553D02*
X2074574Y1362478D01*
G01X2066254Y1378038D02*
X2065474Y1378818D01*
X2064174Y1379403D01*
X2062354Y1379793D01*
X2060794Y1379403D01*
X2059754Y1378623D01*
X2058974Y1377258D01*
Y1371993D01*
X2074574D01*
Y1378428D01*
X2073534Y1379793D01*
X2071974Y1380573D01*
X2070154Y1380963D01*
X2068334Y1380573D01*
X2066774Y1379403D01*
X2066254Y1378038D01*
Y1371993D01*
G01X2074574Y1398278D02*
Y1390478D01*
X2058974D01*
Y1398278D01*
G01X2066514Y1395158D02*
Y1390478D01*
G01X2074574Y1408378D02*
X2058974D01*
Y1413253D01*
X2059754Y1414813D01*
X2060794Y1415788D01*
X2062874Y1416178D01*
X2064954Y1415788D01*
X2066254Y1414618D01*
X2067034Y1413253D01*
Y1408378D01*
G01Y1413253D02*
X2074574Y1416178D01*
G01X2079774Y1429203D02*
X2077174Y1427253D01*
X2074574Y1426278D01*
X2064174D01*
X2061574Y1427253D01*
X2058974Y1429203D01*
G01X2065474Y1451198D02*
X2064434Y1449833D01*
X2064174Y1448663D01*
X2064694Y1447103D01*
X2065734Y1445933D01*
X2067554Y1445153D01*
X2069374Y1444958D01*
X2071194Y1445153D01*
X2072754Y1445933D01*
X2074054Y1447103D01*
X2074574Y1448663D01*
X2074054Y1450028D01*
X2073014Y1451198D01*
G01X2074574Y1462468D02*
X2058974D01*
G01X2066774D02*
X2065214Y1463443D01*
X2064434Y1464613D01*
X2064174Y1465783D01*
X2064694Y1467538D01*
X2065734Y1468708D01*
X2067554Y1469488D01*
X2069634D01*
X2071714Y1469098D01*
X2073274Y1468318D01*
X2074314Y1466953D01*
X2074574Y1465783D01*
X2074314Y1464613D01*
X2073534Y1463443D01*
X2072234Y1462468D01*
G01X2064174Y1480953D02*
X2074574Y1486803D01*
G01X2064174D02*
X2074574Y1480953D01*
G01Y1501778D02*
X2058974D01*
X2062094Y1499438D01*
G01X2074574D02*
Y1504118D01*
G01Y1519678D02*
X2074314Y1521043D01*
X2073534Y1522603D01*
X2072234Y1523578D01*
X2070414Y1523968D01*
X2068594Y1523578D01*
X2067034Y1522408D01*
X2066254Y1520653D01*
Y1518703D01*
X2065734Y1517533D01*
X2064434Y1516558D01*
X2062614Y1516168D01*
X2060794Y1516753D01*
X2059494Y1518118D01*
X2058974Y1519678D01*
X2059494Y1521238D01*
X2060794Y1522603D01*
X2062614Y1523188D01*
X2064434Y1522798D01*
X2065734Y1521823D01*
X2066254Y1520653D01*
Y1518703D01*
X2067034Y1516948D01*
X2068594Y1515778D01*
X2070414Y1515388D01*
X2072234Y1515778D01*
X2073534Y1516753D01*
X2074314Y1518313D01*
X2074574Y1519678D01*
G01X2058974Y1537578D02*
X2059494Y1536018D01*
X2060794Y1534848D01*
X2062354Y1534068D01*
X2064434Y1533483D01*
X2066774Y1533288D01*
X2069114Y1533483D01*
X2071194Y1534068D01*
X2072754Y1534848D01*
X2074054Y1536018D01*
X2074574Y1537578D01*
X2074054Y1539138D01*
X2072754Y1540308D01*
X2071194Y1541088D01*
X2069114Y1541673D01*
X2066774Y1541868D01*
X2064434Y1541673D01*
X2062354Y1541088D01*
X2060794Y1540308D01*
X2059494Y1539138D01*
X2058974Y1537578D01*
G01X2074574Y1557818D02*
X2058974D01*
X2070154Y1550603D01*
Y1560353D01*
G01X2072754Y1570063D02*
X2074054Y1571428D01*
X2074574Y1572988D01*
X2074054Y1574548D01*
X2072494Y1575913D01*
X2070154Y1576888D01*
X2067814Y1577278D01*
X2064954D01*
X2062614Y1576888D01*
X2060534Y1575913D01*
X2059494Y1574743D01*
X2058974Y1573378D01*
X2059494Y1571818D01*
X2060534Y1570648D01*
X2062094Y1569868D01*
X2064174Y1569478D01*
X2065994Y1569868D01*
X2067814Y1570843D01*
X2068854Y1572013D01*
X2069114Y1573378D01*
X2068594Y1574938D01*
X2067294Y1576108D01*
X2064954Y1577278D01*
G01X2074574Y1594788D02*
X2064174D01*
G01X2065994D02*
X2064954Y1594008D01*
X2064434Y1592838D01*
X2064174Y1591473D01*
X2064694Y1590108D01*
X2065734Y1588938D01*
X2067294Y1588158D01*
X2069374Y1587768D01*
X2071454Y1588158D01*
X2073014Y1588938D01*
X2074054Y1590108D01*
X2074574Y1591473D01*
X2074314Y1592838D01*
X2073534Y1594008D01*
X2072494Y1594788D01*
G01X2079774Y1610153D02*
X2077174Y1612103D01*
X2074574Y1613078D01*
X2064174D01*
X2061574Y1612103D01*
X2058974Y1610153D01*
G01X2057274Y1727746D02*
X2056494Y1726576D01*
X2055974Y1725211D01*
Y1723651D01*
X2056754Y1721896D01*
X2058054Y1720531D01*
X2059614Y1719556D01*
X2062214Y1718776D01*
X2064554Y1718581D01*
X2066894Y1718971D01*
X2068454Y1719556D01*
X2070014Y1720726D01*
X2071054Y1722091D01*
X2071574Y1723456D01*
Y1724821D01*
X2071054Y1726186D01*
X2070274Y1727356D01*
X2069234Y1728331D01*
G01X2063254Y1742916D02*
X2062474Y1743696D01*
X2061174Y1744281D01*
X2059354Y1744671D01*
X2057794Y1744281D01*
X2056754Y1743501D01*
X2055974Y1742136D01*
Y1736871D01*
X2071574D01*
Y1743306D01*
X2070534Y1744671D01*
X2068974Y1745451D01*
X2067154Y1745841D01*
X2065334Y1745451D01*
X2063774Y1744281D01*
X2063254Y1742916D01*
Y1736871D01*
G01X2088139Y-29134D02*
G03I-6250J0D01*
G01Y1803261D02*
G03I-6250J0D01*
G01X2135324Y843664D02*
X2122824D01*
X2125324Y841804D01*
G01X2135324D02*
Y845524D01*
G01Y856064D02*
X2135116Y857149D01*
X2134491Y858389D01*
X2133449Y859164D01*
X2131991Y859474D01*
X2130533Y859164D01*
X2129282Y858234D01*
X2128657Y856839D01*
Y855289D01*
X2128241Y854359D01*
X2127199Y853584D01*
X2125741Y853274D01*
X2124282Y853739D01*
X2123241Y854824D01*
X2122824Y856064D01*
X2123241Y857304D01*
X2124282Y858389D01*
X2125741Y858854D01*
X2127199Y858544D01*
X2128241Y857769D01*
X2128657Y856839D01*
Y855289D01*
X2129282Y853894D01*
X2130533Y852964D01*
X2131991Y852654D01*
X2133449Y852964D01*
X2134491Y853739D01*
X2135116Y854979D01*
X2135324Y856064D01*
G01Y868154D02*
X2132616Y868464D01*
X2130324Y868929D01*
X2128241Y869549D01*
X2125949Y870324D01*
X2122824Y871564D01*
Y865364D01*
G01X2135324Y880864D02*
X2122824D01*
X2125324Y879004D01*
G01X2135324D02*
Y882724D01*
G01Y892954D02*
X2132616Y893264D01*
X2130324Y893729D01*
X2128241Y894349D01*
X2125949Y895124D01*
X2122824Y896364D01*
Y890164D01*
G01X2135741Y905664D02*
X2135532Y905354D01*
X2135116D01*
X2134907Y905664D01*
X2135116Y905974D01*
X2135532D01*
X2135741Y905664D01*
G01X2130116Y915119D02*
X2128657Y916204D01*
X2127824Y917134D01*
X2127407Y918374D01*
X2127824Y919459D01*
X2128657Y920234D01*
X2129907Y920854D01*
X2131366Y921009D01*
X2132616Y920854D01*
X2133866Y920234D01*
X2134907Y919304D01*
X2135324Y918219D01*
X2134907Y916979D01*
X2133658Y915894D01*
X2131782Y915274D01*
X2129699Y915119D01*
X2126991Y915429D01*
X2125532Y915894D01*
X2124074Y916669D01*
X2123032Y917754D01*
X2122824Y918839D01*
X2123241Y919924D01*
X2124282Y920699D01*
G01X2133449Y927054D02*
X2134491Y927984D01*
X2135116Y929069D01*
X2135324Y930464D01*
X2134907Y931859D01*
X2134074Y932944D01*
X2132616Y933719D01*
X2130949Y933874D01*
X2129282Y933564D01*
X2128241Y932789D01*
X2127407Y931704D01*
X2127199Y930619D01*
X2127407Y929534D01*
X2128241Y928139D01*
X2122824Y928604D01*
Y932789D01*
G01X2160324Y858074D02*
X2147824D01*
X2156782Y852339D01*
Y860089D01*
G01X2160324Y868304D02*
X2157616Y868614D01*
X2155324Y869079D01*
X2153241Y869699D01*
X2150949Y870474D01*
X2147824Y871714D01*
Y865514D01*
G01X2158449Y877604D02*
X2159491Y878534D01*
X2160116Y879619D01*
X2160324Y881014D01*
X2159907Y882409D01*
X2159074Y883494D01*
X2157616Y884269D01*
X2155949Y884424D01*
X2154282Y884114D01*
X2153241Y883339D01*
X2152407Y882254D01*
X2152199Y881169D01*
X2152407Y880084D01*
X2153241Y878689D01*
X2147824Y879154D01*
Y883339D01*
G01X2160741Y893414D02*
X2160532Y893104D01*
X2160116D01*
X2159907Y893414D01*
X2160116Y893724D01*
X2160532D01*
X2160741Y893414D01*
G01X2160324Y907674D02*
X2147824D01*
X2156782Y901939D01*
Y909689D01*
G01X2157824Y914804D02*
X2159283Y915734D01*
X2160116Y916974D01*
X2160324Y918369D01*
X2160116Y919609D01*
X2159074Y920849D01*
X2157824Y921624D01*
X2156574Y921779D01*
X2155116Y921469D01*
X2154074Y920384D01*
X2153657Y919299D01*
Y917904D01*
G01Y919299D02*
X2153032Y920229D01*
X2151991Y921004D01*
X2150741Y921314D01*
X2149491Y921004D01*
X2148449Y920229D01*
X2147824Y918834D01*
X2148032Y917439D01*
X2148866Y916044D01*
G01X2435255Y234865D02*
X2679664D01*
Y-49150D01*
X2435255D01*
Y234865D01*
G01X2482499Y83440D02*
G03I-5906J0D01*
G01X2482292Y181943D02*
G03I-6250J0D01*
G01X2490767Y10212D02*
X2500215D01*
G02Y2338I0J-3937D01*
G01X2490767D01*
G01X2519900Y10212D02*
G03Y2338I0J-3937D01*
G01X2529349D01*
G01X2519900Y10212D02*
X2529349D01*
M02*
